G04 ================== begin FILE IDENTIFICATION RECORD ==================*
G04 Layout Name:  t6m_pdb_d_0928_1400_274.brd*
G04 Film Name:    smt.art*
G04 File Format:  Gerber RS274X*
G04 File Origin:  Cadence Allegro 16.3-S048*
G04 Origin Date:  Tue Nov 26 11:01:50 2013*
G04 *
G04 Layer:  DRAWING FORMAT/TITLE_BLOCK*
G04 Layer:  VIA CLASS/SOLDERMASK_TOP*
G04 Layer:  PIN/SOLDERMASK_TOP*
G04 Layer:  PACKAGE GEOMETRY/SOLDERMASK_TOP*
G04 Layer:  MANUFACTURING/PHOTOPLOT_OUTLINE*
G04 Layer:  DRAWING FORMAT/TITLE_DATA_SMT*
G04 Layer:  BOARD GEOMETRY/SOLDERMASK_TOP*
G04 *
G04 Offset:    (0.00 0.00)*
G04 Mirror:    No*
G04 Mode:      Positive*
G04 Rotation:  0*
G04 FullContactRelief:  No*
G04 UndefLineWidth:     6.00*
G04 ================== end FILE IDENTIFICATION RECORD ====================*
%FSLAX25Y25*MOIN*%
%IR0*IPPOS*OFA0.00000B0.00000*MIA0B0*SFA1.00000B1.00000*%
%ADD34C,.05*%
%ADD25C,.034*%
%ADD19C,.044*%
%ADD23C,.081*%
%ADD17C,.064*%
%ADD13C,.056*%
%ADD33R,.05X.05*%
%ADD30C,.068*%
%ADD10C,.059*%
%ADD21R,.044X.044*%
%ADD24R,.081X.081*%
%ADD15C,.097*%
%ADD18R,.064X.064*%
%ADD22R,.056X.056*%
%ADD31R,.068X.068*%
%ADD12R,.059X.059*%
%ADD16R,.024X.022*%
%ADD28R,.022X.024*%
%ADD37O,.225X.264*%
%ADD35R,.032X.036*%
%ADD20C,.115*%
%ADD11C,.152*%
%ADD36C,.225*%
%ADD29R,.026X.072*%
%ADD27C,.118*%
%ADD38C,.335*%
%ADD32C,.119*%
%ADD14C,.146*%
%ADD26C,.178*%
%ADD39C,.02*%
%ADD40C,.006*%
%ADD41C,.194*%
G75*
%LPD*%
G75*
G36*
G01X65354Y95060D02*
G02I0J19900D01*
G37*
G36*
G01Y445060D02*
G02I0J19900D01*
G37*
G36*
G01Y795060D02*
G02I0J19900D01*
G37*
G36*
G01Y1145060D02*
G02I0J19900D01*
G37*
G36*
G01Y1495060D02*
G02I0J19900D01*
G37*
G36*
G01Y1845060D02*
G02I0J19900D01*
G37*
G36*
G01X62237Y878761D02*
G03I-5900J0D01*
G37*
G36*
G01X326986Y127165D02*
G02I-19900J0D01*
G37*
G36*
G01Y477165D02*
G02I-19900J0D01*
G37*
G36*
G01Y827165D02*
G02I-19900J0D01*
G37*
G36*
G01Y1343504D02*
G02I-19900J0D01*
G37*
G36*
G01Y1693504D02*
G02I-19900J0D01*
G37*
G36*
G01X326987Y2043503D02*
G02I-19900J0D01*
G37*
G36*
G01X394491Y62106D02*
G03I-5900J0D01*
G37*
G36*
G01X391516Y1991570D02*
G03I-5900J0D01*
G37*
%LPC*%
G75*
G54D41*
X65354Y114960D03*
Y464960D03*
Y814960D03*
Y1164960D03*
Y1514960D03*
Y1864960D03*
X307086Y127165D03*
Y477165D03*
Y827165D03*
Y1343504D03*
Y1693504D03*
X307087Y2043503D03*
%LPD*%
G75*
G54D10*
X17735Y24953D03*
X27735D03*
X22735Y34953D03*
Y216976D03*
X27735Y206976D03*
X17735Y233811D03*
X27735D03*
X22735Y243811D03*
X27735Y415834D03*
X22735Y425834D03*
Y1957291D03*
X27735Y1947291D03*
X22735Y2061661D03*
X27735Y2051661D03*
X37735Y24953D03*
X47735D03*
X32735Y34953D03*
X42735D03*
Y216976D03*
X32735D03*
X47735Y206976D03*
X37735D03*
Y233811D03*
X47735D03*
X32735Y243811D03*
X42735D03*
X47735Y415834D03*
X37735D03*
X42735Y425834D03*
X32735D03*
X42735Y1957291D03*
X32735D03*
X47735Y1947291D03*
X37735D03*
X42735Y2061661D03*
X32735D03*
X47735Y2051661D03*
X37735D03*
X52735Y216976D03*
Y425834D03*
Y1957291D03*
Y2061661D03*
X189762Y73105D03*
X190289Y152050D03*
X190357Y247568D03*
X190817Y331786D03*
X189761Y421732D03*
X190553Y506517D03*
X192888Y598130D03*
X190816Y681645D03*
X191846Y774526D03*
X191606Y856244D03*
X196311Y947202D03*
X195516Y1032544D03*
X191250Y1122856D03*
X191342Y1206233D03*
X191846Y1299104D03*
X190552Y1380966D03*
X189463Y1474162D03*
X191079Y1557277D03*
X192143Y1648177D03*
X191607Y1731351D03*
X191530Y1823227D03*
X190289Y1900420D03*
X192125Y1998730D03*
X191530Y2043388D03*
G54D11*
X12735Y59953D03*
Y181976D03*
Y268811D03*
Y390834D03*
Y1922291D03*
Y2026661D03*
X57735Y59953D03*
Y181976D03*
Y268811D03*
Y390834D03*
Y1922291D03*
Y2026661D03*
G54D20*
X20468Y696341D03*
Y984333D03*
X20472Y1054606D03*
Y1342598D03*
G54D12*
X17735Y206976D03*
Y415834D03*
Y1947291D03*
Y2051661D03*
X52735Y34953D03*
Y243811D03*
X203542Y73105D03*
X204069Y152050D03*
X204137Y247568D03*
X204597Y331786D03*
X203541Y421732D03*
X204333Y506517D03*
X206668Y598130D03*
X204596Y681645D03*
X205626Y774526D03*
X205386Y856244D03*
X210091Y947202D03*
X209296Y1032544D03*
X205030Y1122856D03*
X205122Y1206233D03*
X205626Y1299104D03*
X204332Y1380966D03*
X203243Y1474162D03*
X204859Y1557277D03*
X205923Y1648177D03*
X205387Y1731351D03*
X205310Y1823227D03*
X204069Y1900420D03*
X205905Y1998730D03*
X205310Y2043388D03*
G54D21*
X25389Y1030199D03*
X25393Y1388464D03*
G54D30*
X119920Y18071D03*
Y28071D03*
Y38071D03*
Y48071D03*
Y58071D03*
Y68071D03*
Y78071D03*
Y88071D03*
Y98071D03*
Y108071D03*
Y118071D03*
Y128071D03*
Y138071D03*
Y148071D03*
Y158071D03*
Y168071D03*
Y178071D03*
Y188071D03*
Y198071D03*
Y208071D03*
Y218071D03*
Y228071D03*
Y238071D03*
Y248071D03*
Y258071D03*
Y268071D03*
Y278071D03*
Y288071D03*
Y298071D03*
Y308071D03*
Y318071D03*
Y366102D03*
Y376102D03*
Y386102D03*
Y396102D03*
Y406102D03*
Y416102D03*
Y426102D03*
Y436102D03*
Y446102D03*
Y456102D03*
Y466102D03*
Y476102D03*
Y486102D03*
Y496102D03*
Y506102D03*
Y516102D03*
Y526102D03*
Y536102D03*
Y546102D03*
Y556102D03*
Y566102D03*
Y576102D03*
Y586102D03*
Y596102D03*
Y606102D03*
Y616102D03*
Y626102D03*
Y636102D03*
Y646102D03*
Y656102D03*
Y666102D03*
Y714134D03*
Y724134D03*
Y734134D03*
Y744134D03*
Y754134D03*
Y764134D03*
Y774134D03*
Y784134D03*
Y794134D03*
Y804134D03*
Y814134D03*
Y824134D03*
Y834134D03*
Y844134D03*
Y854134D03*
Y864134D03*
Y874134D03*
Y884134D03*
Y894134D03*
Y904134D03*
Y914134D03*
Y924134D03*
Y934134D03*
Y944134D03*
Y954134D03*
Y964134D03*
Y974134D03*
Y984134D03*
Y994134D03*
Y1004134D03*
Y1014134D03*
Y1062165D03*
Y1072165D03*
Y1082165D03*
Y1092165D03*
Y1102165D03*
Y1112165D03*
Y1122165D03*
Y1132165D03*
Y1142165D03*
Y1152165D03*
Y1162165D03*
Y1172165D03*
Y1182165D03*
Y1192165D03*
Y1202165D03*
Y1212165D03*
Y1222165D03*
Y1232165D03*
Y1242165D03*
Y1252165D03*
Y1262165D03*
Y1272165D03*
Y1282165D03*
Y1292165D03*
Y1302165D03*
Y1312165D03*
Y1322165D03*
Y1332165D03*
Y1342165D03*
Y1352165D03*
Y1362165D03*
Y1410197D03*
Y1420197D03*
Y1430197D03*
Y1440197D03*
Y1450197D03*
Y1460197D03*
Y1470197D03*
Y1480197D03*
Y1490197D03*
Y1500197D03*
Y1510197D03*
Y1520197D03*
Y1530197D03*
Y1540197D03*
Y1550197D03*
Y1560197D03*
Y1570197D03*
Y1580197D03*
Y1590197D03*
Y1600197D03*
Y1610197D03*
Y1620197D03*
Y1630197D03*
Y1640197D03*
Y1650197D03*
Y1660197D03*
Y1670197D03*
Y1680197D03*
Y1690197D03*
Y1700197D03*
Y1710197D03*
Y1758228D03*
Y1768228D03*
Y1778228D03*
Y1788228D03*
Y1798228D03*
Y1808228D03*
Y1818228D03*
Y1828228D03*
Y1838228D03*
Y1848228D03*
Y1858228D03*
Y1868228D03*
Y1878228D03*
Y1888228D03*
Y1898228D03*
Y1908228D03*
Y1918228D03*
Y1928228D03*
Y1938228D03*
Y1948228D03*
Y1958228D03*
Y1968228D03*
Y1978228D03*
Y1988228D03*
Y1998228D03*
Y2008228D03*
Y2018228D03*
Y2028228D03*
Y2038228D03*
Y2048228D03*
Y2058228D03*
X139920Y28071D03*
Y18071D03*
Y58071D03*
Y48071D03*
Y38071D03*
Y78071D03*
Y68071D03*
Y98071D03*
Y88071D03*
Y128071D03*
Y118071D03*
Y108071D03*
Y148071D03*
Y138071D03*
Y178071D03*
Y168071D03*
Y158071D03*
Y198071D03*
Y188071D03*
Y228071D03*
Y218071D03*
Y208071D03*
Y248071D03*
Y238071D03*
Y268071D03*
Y258071D03*
Y298071D03*
Y288071D03*
Y278071D03*
Y318071D03*
Y308071D03*
Y328071D03*
Y366102D03*
Y396102D03*
Y386102D03*
Y376102D03*
Y416102D03*
Y406102D03*
Y436102D03*
Y426102D03*
Y466102D03*
Y456102D03*
Y446102D03*
Y486102D03*
Y476102D03*
Y516102D03*
Y506102D03*
Y496102D03*
Y536102D03*
Y526102D03*
Y566102D03*
Y556102D03*
Y546102D03*
Y586102D03*
Y576102D03*
Y606102D03*
Y596102D03*
Y636102D03*
Y626102D03*
Y616102D03*
Y656102D03*
Y646102D03*
Y676102D03*
Y666102D03*
Y734134D03*
Y724134D03*
Y714134D03*
Y754134D03*
Y744134D03*
Y774134D03*
Y764134D03*
Y804134D03*
Y794134D03*
Y784134D03*
Y824134D03*
Y814134D03*
Y854134D03*
Y844134D03*
Y834134D03*
Y874134D03*
Y864134D03*
Y904134D03*
Y894134D03*
Y884134D03*
Y924134D03*
Y914134D03*
Y944134D03*
Y934134D03*
Y974134D03*
Y964134D03*
Y954134D03*
Y994134D03*
Y984134D03*
Y1024134D03*
Y1014134D03*
Y1004134D03*
Y1072165D03*
Y1062165D03*
Y1092165D03*
Y1082165D03*
Y1122165D03*
Y1112165D03*
Y1102165D03*
Y1142165D03*
Y1132165D03*
Y1162165D03*
Y1152165D03*
Y1192165D03*
Y1182165D03*
Y1172165D03*
Y1212165D03*
Y1202165D03*
Y1242165D03*
Y1232165D03*
Y1222165D03*
Y1262165D03*
Y1252165D03*
Y1282165D03*
Y1272165D03*
Y1312165D03*
Y1302165D03*
Y1292165D03*
Y1332165D03*
Y1322165D03*
Y1362165D03*
Y1352165D03*
Y1342165D03*
Y1372165D03*
Y1410197D03*
Y1430197D03*
Y1420197D03*
Y1460197D03*
Y1450197D03*
Y1440197D03*
Y1480197D03*
Y1470197D03*
Y1500197D03*
Y1490197D03*
Y1530197D03*
Y1520197D03*
Y1510197D03*
Y1550197D03*
Y1540197D03*
Y1580197D03*
Y1570197D03*
Y1560197D03*
Y1600197D03*
Y1590197D03*
Y1620197D03*
Y1610197D03*
Y1650197D03*
Y1640197D03*
Y1630197D03*
Y1670197D03*
Y1660197D03*
Y1700197D03*
Y1690197D03*
Y1680197D03*
Y1720197D03*
Y1710197D03*
Y1768228D03*
Y1758228D03*
Y1798228D03*
Y1788228D03*
Y1778228D03*
Y1818228D03*
Y1808228D03*
Y1838228D03*
Y1828228D03*
Y1868228D03*
Y1858228D03*
Y1848228D03*
Y1888228D03*
Y1878228D03*
Y1918228D03*
Y1908228D03*
Y1898228D03*
Y1938228D03*
Y1928228D03*
Y1958228D03*
Y1948228D03*
Y1988228D03*
Y1978228D03*
Y1968228D03*
Y2008228D03*
Y1998228D03*
Y2038228D03*
Y2028228D03*
Y2018228D03*
Y2058228D03*
Y2048228D03*
Y2068228D03*
G54D40*
G01X-723776Y2987387D02*
Y-376795D01*
Y-489221D01*
X1782976D01*
Y-376795D01*
Y2987387D01*
X-723776D01*
G01X-4000Y-62500D02*
Y-137500D01*
X496000D01*
Y-62500D01*
X-4000D01*
G01X8000Y-127500D02*
Y-132500D01*
G01X6543Y-127500D02*
X9457D01*
G01X14367Y-132500D02*
X11833D01*
Y-127500D01*
X14367D01*
G01X13353Y-129917D02*
X11833D01*
G01X16933Y-127500D02*
Y-132500D01*
X19467D01*
G01X23300Y-132667D02*
X23173Y-132583D01*
Y-132417D01*
X23300Y-132333D01*
X23427Y-132417D01*
Y-132583D01*
X23300Y-132667D01*
G01Y-130417D02*
X23173Y-130333D01*
Y-130167D01*
X23300Y-130083D01*
X23427Y-130167D01*
Y-130333D01*
X23300Y-130417D01*
G01X28083Y-134167D02*
X27450Y-133333D01*
X27133Y-132500D01*
Y-129167D01*
X27450Y-128333D01*
X28083Y-127500D01*
G01X33500D02*
X32993Y-127667D01*
X32613Y-128083D01*
X32360Y-128583D01*
X32170Y-129250D01*
X32107Y-130000D01*
X32170Y-130750D01*
X32360Y-131417D01*
X32613Y-131917D01*
X32993Y-132333D01*
X33500Y-132500D01*
X34007Y-132333D01*
X34387Y-131917D01*
X34640Y-131417D01*
X34830Y-130750D01*
X34893Y-130000D01*
X34830Y-129250D01*
X34640Y-128583D01*
X34387Y-128083D01*
X34007Y-127667D01*
X33500Y-127500D01*
G01X37207Y-131500D02*
X37587Y-132083D01*
X38093Y-132417D01*
X38663Y-132500D01*
X39170Y-132417D01*
X39677Y-132000D01*
X39993Y-131500D01*
X40057Y-131000D01*
X39930Y-130417D01*
X39487Y-130000D01*
X39043Y-129833D01*
X38473D01*
G01X39043D02*
X39423Y-129583D01*
X39740Y-129167D01*
X39867Y-128667D01*
X39740Y-128167D01*
X39423Y-127750D01*
X38853Y-127500D01*
X38283Y-127583D01*
X37713Y-127917D01*
G01X44017Y-134167D02*
X44650Y-133333D01*
X44967Y-132500D01*
Y-129167D01*
X44650Y-128333D01*
X44017Y-127500D01*
G01X47407Y-131500D02*
X47787Y-132083D01*
X48293Y-132417D01*
X48863Y-132500D01*
X49370Y-132417D01*
X49877Y-132000D01*
X50193Y-131500D01*
X50257Y-131000D01*
X50130Y-130417D01*
X49687Y-130000D01*
X49243Y-129833D01*
X48673D01*
G01X49243D02*
X49623Y-129583D01*
X49940Y-129167D01*
X50067Y-128667D01*
X49940Y-128167D01*
X49623Y-127750D01*
X49053Y-127500D01*
X48483Y-127583D01*
X47913Y-127917D01*
G01X52697Y-128333D02*
X53077Y-127833D01*
X53520Y-127583D01*
X54027Y-127500D01*
X54660Y-127667D01*
X55103Y-128083D01*
X55230Y-128583D01*
X55167Y-129083D01*
X54913Y-129500D01*
X53647Y-130333D01*
X53077Y-130917D01*
X52697Y-131750D01*
X52570Y-132500D01*
X55230D01*
G01X58873D02*
X59000Y-131417D01*
X59190Y-130500D01*
X59443Y-129667D01*
X59760Y-128750D01*
X60267Y-127500D01*
X57733D01*
G01X63277Y-130833D02*
X64923D01*
G01X67997Y-128333D02*
X68377Y-127833D01*
X68820Y-127583D01*
X69327Y-127500D01*
X69960Y-127667D01*
X70403Y-128083D01*
X70530Y-128583D01*
X70467Y-129083D01*
X70213Y-129500D01*
X68947Y-130333D01*
X68377Y-130917D01*
X67997Y-131750D01*
X67870Y-132500D01*
X70530D01*
G01X72907Y-131500D02*
X73287Y-132083D01*
X73793Y-132417D01*
X74363Y-132500D01*
X74870Y-132417D01*
X75377Y-132000D01*
X75693Y-131500D01*
X75757Y-131000D01*
X75630Y-130417D01*
X75187Y-130000D01*
X74743Y-129833D01*
X74173D01*
G01X74743D02*
X75123Y-129583D01*
X75440Y-129167D01*
X75567Y-128667D01*
X75440Y-128167D01*
X75123Y-127750D01*
X74553Y-127500D01*
X73983Y-127583D01*
X73413Y-127917D01*
G01X80160Y-132500D02*
Y-127500D01*
X77817Y-131083D01*
X80983D01*
G01X83107Y-131750D02*
X83487Y-132167D01*
X83930Y-132417D01*
X84500Y-132500D01*
X85070Y-132333D01*
X85513Y-132000D01*
X85830Y-131417D01*
X85893Y-130750D01*
X85767Y-130083D01*
X85450Y-129667D01*
X85007Y-129333D01*
X84563Y-129250D01*
X84120Y-129333D01*
X83550Y-129667D01*
X83740Y-127500D01*
X85450D01*
G01X93497Y-132500D02*
Y-127500D01*
X95903D01*
G01X95017Y-129917D02*
X93497D01*
G01X98217Y-132500D02*
X99800Y-127500D01*
X101383Y-132500D01*
G01X100813Y-130750D02*
X98787D01*
G01X103570Y-132500D02*
X106230Y-127500D01*
G01X103570D02*
X106230Y-132500D01*
G01X110000Y-132667D02*
X109873Y-132583D01*
Y-132417D01*
X110000Y-132333D01*
X110127Y-132417D01*
Y-132583D01*
X110000Y-132667D01*
G01Y-130417D02*
X109873Y-130333D01*
Y-130167D01*
X110000Y-130083D01*
X110127Y-130167D01*
Y-130333D01*
X110000Y-130417D01*
G01X114783Y-134167D02*
X114150Y-133333D01*
X113833Y-132500D01*
Y-129167D01*
X114150Y-128333D01*
X114783Y-127500D01*
G01X120200D02*
X119693Y-127667D01*
X119313Y-128083D01*
X119060Y-128583D01*
X118870Y-129250D01*
X118807Y-130000D01*
X118870Y-130750D01*
X119060Y-131417D01*
X119313Y-131917D01*
X119693Y-132333D01*
X120200Y-132500D01*
X120707Y-132333D01*
X121087Y-131917D01*
X121340Y-131417D01*
X121530Y-130750D01*
X121593Y-130000D01*
X121530Y-129250D01*
X121340Y-128583D01*
X121087Y-128083D01*
X120707Y-127667D01*
X120200Y-127500D01*
G01X123907Y-131500D02*
X124287Y-132083D01*
X124793Y-132417D01*
X125363Y-132500D01*
X125870Y-132417D01*
X126377Y-132000D01*
X126693Y-131500D01*
X126757Y-131000D01*
X126630Y-130417D01*
X126187Y-130000D01*
X125743Y-129833D01*
X125173D01*
G01X125743D02*
X126123Y-129583D01*
X126440Y-129167D01*
X126567Y-128667D01*
X126440Y-128167D01*
X126123Y-127750D01*
X125553Y-127500D01*
X124983Y-127583D01*
X124413Y-127917D01*
G01X130717Y-134167D02*
X131350Y-133333D01*
X131667Y-132500D01*
Y-129167D01*
X131350Y-128333D01*
X130717Y-127500D01*
G01X134107Y-131500D02*
X134487Y-132083D01*
X134993Y-132417D01*
X135563Y-132500D01*
X136070Y-132417D01*
X136577Y-132000D01*
X136893Y-131500D01*
X136957Y-131000D01*
X136830Y-130417D01*
X136387Y-130000D01*
X135943Y-129833D01*
X135373D01*
G01X135943D02*
X136323Y-129583D01*
X136640Y-129167D01*
X136767Y-128667D01*
X136640Y-128167D01*
X136323Y-127750D01*
X135753Y-127500D01*
X135183Y-127583D01*
X134613Y-127917D01*
G01X139523Y-131917D02*
X139967Y-132333D01*
X140473Y-132500D01*
X140980Y-132333D01*
X141423Y-131833D01*
X141740Y-131083D01*
X141867Y-130333D01*
Y-129417D01*
X141740Y-128667D01*
X141423Y-128000D01*
X141043Y-127667D01*
X140600Y-127500D01*
X140093Y-127667D01*
X139713Y-128000D01*
X139460Y-128500D01*
X139333Y-129167D01*
X139460Y-129750D01*
X139777Y-130333D01*
X140157Y-130667D01*
X140600Y-130750D01*
X141107Y-130583D01*
X141487Y-130167D01*
X141867Y-129417D01*
G01X145573Y-132500D02*
X145700Y-131417D01*
X145890Y-130500D01*
X146143Y-129667D01*
X146460Y-128750D01*
X146967Y-127500D01*
X144433D01*
G01X149977Y-130833D02*
X151623D01*
G01X154507Y-131500D02*
X154887Y-132083D01*
X155393Y-132417D01*
X155963Y-132500D01*
X156470Y-132417D01*
X156977Y-132000D01*
X157293Y-131500D01*
X157357Y-131000D01*
X157230Y-130417D01*
X156787Y-130000D01*
X156343Y-129833D01*
X155773D01*
G01X156343D02*
X156723Y-129583D01*
X157040Y-129167D01*
X157167Y-128667D01*
X157040Y-128167D01*
X156723Y-127750D01*
X156153Y-127500D01*
X155583Y-127583D01*
X155013Y-127917D01*
G01X159797Y-130417D02*
X160240Y-129833D01*
X160620Y-129500D01*
X161127Y-129333D01*
X161570Y-129500D01*
X161887Y-129833D01*
X162140Y-130333D01*
X162203Y-130917D01*
X162140Y-131417D01*
X161887Y-131917D01*
X161507Y-132333D01*
X161063Y-132500D01*
X160557Y-132333D01*
X160113Y-131833D01*
X159860Y-131083D01*
X159797Y-130250D01*
X159923Y-129167D01*
X160113Y-128583D01*
X160430Y-128000D01*
X160873Y-127583D01*
X161317Y-127500D01*
X161760Y-127667D01*
X162077Y-128083D01*
G01X166100Y-132500D02*
Y-127500D01*
X165340Y-128500D01*
G01Y-132500D02*
X166860D01*
G01X171960D02*
Y-127500D01*
X169617Y-131083D01*
X172783D01*
G01X191000Y-62500D02*
Y-137500D01*
G01Y-112500D02*
X294000D01*
Y-87500D01*
G01X191000D02*
X294000D01*
G01X301507Y-122500D02*
Y-117500D01*
X302773D01*
X303280Y-117750D01*
X303660Y-118083D01*
X303977Y-118583D01*
X304230Y-119167D01*
X304293Y-120000D01*
X304230Y-120833D01*
X303977Y-121417D01*
X303660Y-121917D01*
X303280Y-122250D01*
X302773Y-122500D01*
X301507D01*
G01X306417D02*
X308000Y-117500D01*
X309583Y-122500D01*
G01X309013Y-120750D02*
X306987D01*
G01X313100Y-117500D02*
Y-122500D01*
G01X311643Y-117500D02*
X314557D01*
G01X319467Y-122500D02*
X316933D01*
Y-117500D01*
X319467D01*
G01X318453Y-119917D02*
X316933D01*
G01X323300Y-122667D02*
X323173Y-122583D01*
Y-122417D01*
X323300Y-122333D01*
X323427Y-122417D01*
Y-122583D01*
X323300Y-122667D01*
G01Y-120417D02*
X323173Y-120333D01*
Y-120167D01*
X323300Y-120083D01*
X323427Y-120167D01*
Y-120333D01*
X323300Y-120417D01*
G01X296000Y-62500D02*
Y-137500D01*
G01X294000Y-62500D02*
Y-137500D01*
G01X301633Y-97500D02*
Y-92500D01*
X303153D01*
X303660Y-92750D01*
X304040Y-93333D01*
X304167Y-94000D01*
X304040Y-94667D01*
X303723Y-95167D01*
X303153Y-95417D01*
X301633D01*
G01X306860Y-97667D02*
X309140Y-92500D01*
G01X311643Y-97500D02*
Y-92500D01*
X314557Y-97500D01*
Y-92500D01*
G01X318200Y-97667D02*
X318073Y-97583D01*
Y-97417D01*
X318200Y-97333D01*
X318327Y-97417D01*
Y-97583D01*
X318200Y-97667D01*
G01Y-95417D02*
X318073Y-95333D01*
Y-95167D01*
X318200Y-95083D01*
X318327Y-95167D01*
Y-95333D01*
X318200Y-95417D01*
G01X296000Y-112500D02*
X496000D01*
G01X301633Y-72500D02*
Y-67500D01*
X303153D01*
X303660Y-67750D01*
X304040Y-68333D01*
X304167Y-69000D01*
X304040Y-69667D01*
X303723Y-70167D01*
X303153Y-70417D01*
X301633D01*
G01X306733Y-72500D02*
Y-67500D01*
X308317D01*
X308823Y-67750D01*
X309140Y-68083D01*
X309267Y-68750D01*
X309140Y-69417D01*
X308760Y-69833D01*
X308317Y-70083D01*
X306733D01*
G01X308317D02*
X309267Y-72500D01*
G01X313100D02*
X312593Y-72417D01*
X312150Y-72083D01*
X311770Y-71583D01*
X311517Y-71000D01*
X311390Y-70333D01*
Y-69667D01*
X311517Y-69000D01*
X311770Y-68417D01*
X312150Y-67917D01*
X312593Y-67583D01*
X313100Y-67500D01*
X313607Y-67583D01*
X314050Y-67917D01*
X314430Y-68417D01*
X314683Y-69000D01*
X314810Y-69667D01*
Y-70333D01*
X314683Y-71000D01*
X314430Y-71583D01*
X314050Y-72083D01*
X313607Y-72417D01*
X313100Y-72500D01*
G01X316933Y-71500D02*
X317250Y-72000D01*
X317630Y-72333D01*
X318073Y-72500D01*
X318580Y-72333D01*
X318960Y-72000D01*
X319340Y-71500D01*
X319467Y-70833D01*
Y-67500D01*
G01X324567Y-72500D02*
X322033D01*
Y-67500D01*
X324567D01*
G01X323553Y-69917D02*
X322033D01*
G01X329793Y-67917D02*
X329413Y-67667D01*
X328970Y-67500D01*
X328463D01*
X327893Y-67750D01*
X327450Y-68167D01*
X327133Y-68667D01*
X326880Y-69500D01*
X326817Y-70250D01*
X326943Y-71000D01*
X327133Y-71500D01*
X327513Y-72000D01*
X327957Y-72333D01*
X328400Y-72500D01*
X328843D01*
X329287Y-72333D01*
X329667Y-72083D01*
X329983Y-71750D01*
G01X333500Y-67500D02*
Y-72500D01*
G01X332043Y-67500D02*
X334957D01*
G01X338600Y-72667D02*
X338473Y-72583D01*
Y-72417D01*
X338600Y-72333D01*
X338727Y-72417D01*
Y-72583D01*
X338600Y-72667D01*
G01Y-70417D02*
X338473Y-70333D01*
Y-70167D01*
X338600Y-70083D01*
X338727Y-70167D01*
Y-70333D01*
X338600Y-70417D01*
G01X296000Y-87500D02*
X496000D01*
G01X411000Y-112500D02*
Y-137500D01*
G01X416633Y-122500D02*
Y-117500D01*
X418217D01*
X418723Y-117750D01*
X419040Y-118083D01*
X419167Y-118750D01*
X419040Y-119417D01*
X418660Y-119833D01*
X418217Y-120083D01*
X416633D01*
G01X418217D02*
X419167Y-122500D01*
G01X424267D02*
X421733D01*
Y-117500D01*
X424267D01*
G01X423253Y-119917D02*
X421733D01*
G01X426517Y-117500D02*
X428100Y-122500D01*
X429683Y-117500D01*
G01X433200Y-122667D02*
X433073Y-122583D01*
Y-122417D01*
X433200Y-122333D01*
X433327Y-122417D01*
Y-122583D01*
X433200Y-122667D01*
G01Y-120417D02*
X433073Y-120333D01*
Y-120167D01*
X433200Y-120083D01*
X433327Y-120167D01*
Y-120333D01*
X433200Y-120417D01*
G01X460000Y-112500D02*
Y-137500D01*
G01X-723776Y2987387D02*
Y-376795D01*
Y-489221D01*
X1782976D01*
Y-376795D01*
Y2987387D01*
X-723776D01*
G01X6705Y-124160D02*
X7332Y-124685D01*
X8037Y-125000D01*
X8663D01*
X9290Y-124685D01*
X9760Y-124160D01*
X9995Y-123425D01*
X9838Y-122690D01*
X9447Y-122060D01*
X8742Y-121640D01*
X7802Y-121430D01*
X7253Y-121010D01*
X7018Y-120275D01*
X7175Y-119540D01*
X7567Y-119015D01*
X8115Y-118700D01*
X8663D01*
X9212Y-118910D01*
X9682Y-119435D01*
G01X13005Y-125000D02*
Y-118700D01*
G01X16295D02*
Y-125000D01*
G01Y-121850D02*
X13005D01*
G01X20010Y-118700D02*
X21890D01*
G01X20950D02*
Y-125000D01*
G01X20010D02*
X21890D01*
G01X28817D02*
X25683D01*
Y-118700D01*
X28817D01*
G01X27563Y-121745D02*
X25683D01*
G01X31748Y-125000D02*
Y-118700D01*
X35352Y-125000D01*
Y-118700D01*
G01X39693Y-126155D02*
X40007Y-124790D01*
G01X46150Y-118700D02*
Y-125000D01*
G01X44348Y-118700D02*
X47952D01*
G01X50492Y-125000D02*
X52450Y-118700D01*
X54408Y-125000D01*
G01X53703Y-122795D02*
X51197D01*
G01X57810Y-118700D02*
X59690D01*
G01X58750D02*
Y-125000D01*
G01X57810D02*
X59690D01*
G01X62700Y-118700D02*
X63797Y-125000D01*
X65050Y-118700D01*
X66303Y-125000D01*
X67400Y-118700D01*
G01X69392Y-125000D02*
X71350Y-118700D01*
X73308Y-125000D01*
G01X72603Y-122795D02*
X70097D01*
G01X75848Y-125000D02*
Y-118700D01*
X79452Y-125000D01*
Y-118700D01*
G01X88683Y-125000D02*
Y-118700D01*
X90642D01*
X91268Y-119015D01*
X91660Y-119435D01*
X91817Y-120275D01*
X91660Y-121115D01*
X91190Y-121640D01*
X90642Y-121955D01*
X88683D01*
G01X90642D02*
X91817Y-125000D01*
G01X96550Y-125210D02*
X96393Y-125105D01*
Y-124895D01*
X96550Y-124790D01*
X96707Y-124895D01*
Y-125105D01*
X96550Y-125210D01*
G01X102850Y-125000D02*
X102223Y-124895D01*
X101675Y-124475D01*
X101205Y-123845D01*
X100892Y-123110D01*
X100735Y-122270D01*
Y-121430D01*
X100892Y-120590D01*
X101205Y-119855D01*
X101675Y-119225D01*
X102223Y-118805D01*
X102850Y-118700D01*
X103477Y-118805D01*
X104025Y-119225D01*
X104495Y-119855D01*
X104808Y-120590D01*
X104965Y-121430D01*
Y-122270D01*
X104808Y-123110D01*
X104495Y-123845D01*
X104025Y-124475D01*
X103477Y-124895D01*
X102850Y-125000D01*
G01X109150Y-125210D02*
X108993Y-125105D01*
Y-124895D01*
X109150Y-124790D01*
X109307Y-124895D01*
Y-125105D01*
X109150Y-125210D01*
G01X117173Y-119225D02*
X116703Y-118910D01*
X116155Y-118700D01*
X115528D01*
X114823Y-119015D01*
X114275Y-119540D01*
X113883Y-120170D01*
X113570Y-121220D01*
X113492Y-122165D01*
X113648Y-123110D01*
X113883Y-123740D01*
X114353Y-124370D01*
X114902Y-124790D01*
X115450Y-125000D01*
X115998D01*
X116547Y-124790D01*
X117017Y-124475D01*
X117408Y-124055D01*
G01X121750Y-125210D02*
X121593Y-125105D01*
Y-124895D01*
X121750Y-124790D01*
X121907Y-124895D01*
Y-125105D01*
X121750Y-125210D01*
G01X6627Y-115000D02*
Y-108700D01*
G01X9603D02*
X6627Y-112585D01*
G01X10073Y-115000D02*
X7958Y-110800D01*
G01X12927Y-108700D02*
Y-113215D01*
X13240Y-114160D01*
X13867Y-114790D01*
X14650Y-115000D01*
X15433Y-114790D01*
X16060Y-114160D01*
X16373Y-113215D01*
Y-108700D01*
G01X22517Y-115000D02*
X19383D01*
Y-108700D01*
X22517D01*
G01X21263Y-111745D02*
X19383D01*
G01X26310Y-108700D02*
X28190D01*
G01X27250D02*
Y-115000D01*
G01X26310D02*
X28190D01*
G01X38205Y-114160D02*
X38832Y-114685D01*
X39537Y-115000D01*
X40163D01*
X40790Y-114685D01*
X41260Y-114160D01*
X41495Y-113425D01*
X41338Y-112690D01*
X40947Y-112060D01*
X40242Y-111640D01*
X39302Y-111430D01*
X38753Y-111010D01*
X38518Y-110275D01*
X38675Y-109540D01*
X39067Y-109015D01*
X39615Y-108700D01*
X40163D01*
X40712Y-108910D01*
X41182Y-109435D01*
G01X44505Y-115000D02*
Y-108700D01*
G01X47795D02*
Y-115000D01*
G01Y-111850D02*
X44505D01*
G01X50492Y-115000D02*
X52450Y-108700D01*
X54408Y-115000D01*
G01X53703Y-112795D02*
X51197D01*
G01X56948Y-115000D02*
Y-108700D01*
X60552Y-115000D01*
Y-108700D01*
G01X69705Y-115000D02*
Y-108700D01*
G01X72995D02*
Y-115000D01*
G01Y-111850D02*
X69705D01*
G01X76005Y-114160D02*
X76632Y-114685D01*
X77337Y-115000D01*
X77963D01*
X78590Y-114685D01*
X79060Y-114160D01*
X79295Y-113425D01*
X79138Y-112690D01*
X78747Y-112060D01*
X78042Y-111640D01*
X77102Y-111430D01*
X76553Y-111010D01*
X76318Y-110275D01*
X76475Y-109540D01*
X76867Y-109015D01*
X77415Y-108700D01*
X77963D01*
X78512Y-108910D01*
X78982Y-109435D01*
G01X83010Y-108700D02*
X84890D01*
G01X83950D02*
Y-115000D01*
G01X83010D02*
X84890D01*
G01X88292D02*
X90250Y-108700D01*
X92208Y-115000D01*
G01X91503Y-112795D02*
X88997D01*
G01X94748Y-115000D02*
Y-108700D01*
X98352Y-115000D01*
Y-108700D01*
G01X103320Y-111850D02*
X104887D01*
Y-113740D01*
X104417Y-114370D01*
X103868Y-114790D01*
X103085Y-115000D01*
X102302Y-114790D01*
X101753Y-114370D01*
X101283Y-113740D01*
X100970Y-113005D01*
X100813Y-112165D01*
Y-111430D01*
X100970Y-110800D01*
X101283Y-110065D01*
X101753Y-109435D01*
X102223Y-109015D01*
X102850Y-108700D01*
X103398D01*
X104025Y-108910D01*
X104495Y-109330D01*
G01X108993Y-116155D02*
X109307Y-114790D01*
G01X115450Y-108700D02*
Y-115000D01*
G01X113648Y-108700D02*
X117252D01*
G01X119792Y-115000D02*
X121750Y-108700D01*
X123708Y-115000D01*
G01X123003Y-112795D02*
X120497D01*
G01X128050Y-115000D02*
X127423Y-114895D01*
X126875Y-114475D01*
X126405Y-113845D01*
X126092Y-113110D01*
X125935Y-112270D01*
Y-111430D01*
X126092Y-110590D01*
X126405Y-109855D01*
X126875Y-109225D01*
X127423Y-108805D01*
X128050Y-108700D01*
X128677Y-108805D01*
X129225Y-109225D01*
X129695Y-109855D01*
X130008Y-110590D01*
X130165Y-111430D01*
Y-112270D01*
X130008Y-113110D01*
X129695Y-113845D01*
X129225Y-114475D01*
X128677Y-114895D01*
X128050Y-115000D01*
G01X140650D02*
Y-112165D01*
X139083Y-108700D01*
G01X142217D02*
X140650Y-112165D01*
G01X145227Y-108700D02*
Y-113215D01*
X145540Y-114160D01*
X146167Y-114790D01*
X146950Y-115000D01*
X147733Y-114790D01*
X148360Y-114160D01*
X148673Y-113215D01*
Y-108700D01*
G01X151292Y-115000D02*
X153250Y-108700D01*
X155208Y-115000D01*
G01X154503Y-112795D02*
X151997D01*
G01X157748Y-115000D02*
Y-108700D01*
X161352Y-115000D01*
Y-108700D01*
G01X30650Y-92300D02*
X28130Y-91883D01*
X25925Y-90217D01*
X24035Y-87717D01*
X22775Y-84800D01*
X22145Y-81467D01*
Y-78133D01*
X22775Y-74800D01*
X24035Y-71883D01*
X25925Y-69384D01*
X28130Y-67717D01*
X30650Y-67300D01*
X33170Y-67717D01*
X35375Y-69384D01*
X37265Y-71883D01*
X38525Y-74800D01*
X39155Y-78133D01*
Y-81467D01*
X38525Y-84800D01*
X37265Y-87717D01*
X35375Y-90217D01*
X33170Y-91883D01*
X30650Y-92300D01*
G01X33170Y-85633D02*
X36950Y-92300D01*
G01X50495Y-75634D02*
Y-87300D01*
X51755Y-90217D01*
X53645Y-91883D01*
X55850Y-92300D01*
X58055Y-91883D01*
X59945Y-90217D01*
X61205Y-87300D01*
G01Y-92300D02*
Y-75634D01*
G01X86720Y-92300D02*
Y-75634D01*
G01Y-78550D02*
X85460Y-76884D01*
X83570Y-76050D01*
X81365Y-75634D01*
X79160Y-76467D01*
X77270Y-78133D01*
X76010Y-80634D01*
X75380Y-83967D01*
X76010Y-87300D01*
X77270Y-89801D01*
X79160Y-91467D01*
X81365Y-92300D01*
X83570Y-91883D01*
X85460Y-90634D01*
X86720Y-88967D01*
G01X100895Y-92300D02*
Y-75634D01*
G01Y-79800D02*
X102155Y-77717D01*
X104045Y-76050D01*
X106565Y-75634D01*
X108770Y-76050D01*
X110660Y-77717D01*
X111605Y-80634D01*
Y-92300D01*
G01X131450Y-67300D02*
Y-92300D01*
G01X127040Y-75634D02*
X135860D01*
G01X162320Y-92300D02*
Y-75634D01*
G01Y-78550D02*
X161060Y-76884D01*
X159170Y-76050D01*
X156965Y-75634D01*
X154760Y-76467D01*
X152870Y-78133D01*
X151610Y-80634D01*
X150980Y-83967D01*
X151610Y-87300D01*
X152870Y-89801D01*
X154760Y-91467D01*
X156965Y-92300D01*
X159170Y-91883D01*
X161060Y-90634D01*
X162320Y-88967D01*
G01X6548Y-105000D02*
Y-98700D01*
X10152Y-105000D01*
Y-98700D01*
G01X14650Y-105000D02*
X14023Y-104895D01*
X13475Y-104475D01*
X13005Y-103845D01*
X12692Y-103110D01*
X12535Y-102270D01*
Y-101430D01*
X12692Y-100590D01*
X13005Y-99855D01*
X13475Y-99225D01*
X14023Y-98805D01*
X14650Y-98700D01*
X15277Y-98805D01*
X15825Y-99225D01*
X16295Y-99855D01*
X16608Y-100590D01*
X16765Y-101430D01*
Y-102270D01*
X16608Y-103110D01*
X16295Y-103845D01*
X15825Y-104475D01*
X15277Y-104895D01*
X14650Y-105000D01*
G01X20950Y-105210D02*
X20793Y-105105D01*
Y-104895D01*
X20950Y-104790D01*
X21107Y-104895D01*
Y-105105D01*
X20950Y-105210D01*
G01X27250Y-105000D02*
Y-98700D01*
X26310Y-99960D01*
G01Y-105000D02*
X28190D01*
G01X33550D02*
X34098Y-104895D01*
X34725Y-104580D01*
X35117Y-104055D01*
X35273Y-103320D01*
X35117Y-102585D01*
X34647Y-101955D01*
X33942Y-101640D01*
X33158D01*
X32688Y-101430D01*
X32297Y-100905D01*
X32140Y-100170D01*
X32375Y-99435D01*
X32923Y-98910D01*
X33550Y-98700D01*
X34177Y-98910D01*
X34725Y-99435D01*
X34960Y-100170D01*
X34803Y-100905D01*
X34412Y-101430D01*
X33942Y-101640D01*
X33158D01*
X32453Y-101955D01*
X31983Y-102585D01*
X31827Y-103320D01*
X31983Y-104055D01*
X32375Y-104580D01*
X33002Y-104895D01*
X33550Y-105000D01*
G01X39850D02*
X40398Y-104895D01*
X41025Y-104580D01*
X41417Y-104055D01*
X41573Y-103320D01*
X41417Y-102585D01*
X40947Y-101955D01*
X40242Y-101640D01*
X39458D01*
X38988Y-101430D01*
X38597Y-100905D01*
X38440Y-100170D01*
X38675Y-99435D01*
X39223Y-98910D01*
X39850Y-98700D01*
X40477Y-98910D01*
X41025Y-99435D01*
X41260Y-100170D01*
X41103Y-100905D01*
X40712Y-101430D01*
X40242Y-101640D01*
X39458D01*
X38753Y-101955D01*
X38283Y-102585D01*
X38127Y-103320D01*
X38283Y-104055D01*
X38675Y-104580D01*
X39302Y-104895D01*
X39850Y-105000D01*
G01X45993Y-106155D02*
X46307Y-104790D01*
G01X50100Y-98700D02*
X51197Y-105000D01*
X52450Y-98700D01*
X53703Y-105000D01*
X54800Y-98700D01*
G01X60317Y-105000D02*
X57183D01*
Y-98700D01*
X60317D01*
G01X59063Y-101745D02*
X57183D01*
G01X63248Y-105000D02*
Y-98700D01*
X66852Y-105000D01*
Y-98700D01*
G01X76005Y-105000D02*
Y-98700D01*
G01X79295D02*
Y-105000D01*
G01Y-101850D02*
X76005D01*
G01X81600Y-98700D02*
X82697Y-105000D01*
X83950Y-98700D01*
X85203Y-105000D01*
X86300Y-98700D01*
G01X88292Y-105000D02*
X90250Y-98700D01*
X92208Y-105000D01*
G01X91503Y-102795D02*
X88997D01*
G01X101362Y-99750D02*
X101832Y-99120D01*
X102380Y-98805D01*
X103007Y-98700D01*
X103790Y-98910D01*
X104338Y-99435D01*
X104495Y-100065D01*
X104417Y-100695D01*
X104103Y-101220D01*
X102537Y-102270D01*
X101832Y-103005D01*
X101362Y-104055D01*
X101205Y-105000D01*
X104495D01*
G01X107348D02*
Y-98700D01*
X110952Y-105000D01*
Y-98700D01*
G01X113727Y-105000D02*
Y-98700D01*
X115293D01*
X115920Y-99015D01*
X116390Y-99435D01*
X116782Y-100065D01*
X117095Y-100800D01*
X117173Y-101850D01*
X117095Y-102900D01*
X116782Y-103635D01*
X116390Y-104265D01*
X115920Y-104685D01*
X115293Y-105000D01*
X113727D01*
G01X126483D02*
Y-98700D01*
X128442D01*
X129068Y-99015D01*
X129460Y-99435D01*
X129617Y-100275D01*
X129460Y-101115D01*
X128990Y-101640D01*
X128442Y-101955D01*
X126483D01*
G01X128442D02*
X129617Y-105000D01*
G01X132627D02*
Y-98700D01*
X134193D01*
X134820Y-99015D01*
X135290Y-99435D01*
X135682Y-100065D01*
X135995Y-100800D01*
X136073Y-101850D01*
X135995Y-102900D01*
X135682Y-103635D01*
X135290Y-104265D01*
X134820Y-104685D01*
X134193Y-105000D01*
X132627D01*
G01X140650Y-105210D02*
X140493Y-105105D01*
Y-104895D01*
X140650Y-104790D01*
X140807Y-104895D01*
Y-105105D01*
X140650Y-105210D01*
G01X215400Y-105000D02*
Y-97000D01*
X218000Y-103667D01*
X220600Y-97000D01*
Y-105000D01*
G01X223500D02*
X226000Y-97000D01*
X228500Y-105000D01*
G01X227600Y-102200D02*
X224400D01*
G01X231900Y-103934D02*
X232700Y-104600D01*
X233600Y-105000D01*
X234400D01*
X235200Y-104600D01*
X235800Y-103934D01*
X236100Y-103000D01*
X235900Y-102067D01*
X235400Y-101267D01*
X234500Y-100733D01*
X233300Y-100467D01*
X232600Y-99933D01*
X232300Y-99000D01*
X232500Y-98067D01*
X233000Y-97400D01*
X233700Y-97000D01*
X234400D01*
X235100Y-97267D01*
X235700Y-97933D01*
G01X239800Y-105000D02*
Y-97000D01*
G01X243600D02*
X239800Y-101934D01*
G01X244200Y-105000D02*
X241500Y-99667D01*
G01X248700Y-102333D02*
X251300D01*
G01X258000Y-97000D02*
Y-105000D01*
G01X255700Y-97000D02*
X260300D01*
G01X266000Y-105000D02*
X265200Y-104867D01*
X264500Y-104333D01*
X263900Y-103533D01*
X263500Y-102600D01*
X263300Y-101533D01*
Y-100467D01*
X263500Y-99400D01*
X263900Y-98467D01*
X264500Y-97667D01*
X265200Y-97133D01*
X266000Y-97000D01*
X266800Y-97133D01*
X267500Y-97667D01*
X268100Y-98467D01*
X268500Y-99400D01*
X268700Y-100467D01*
Y-101533D01*
X268500Y-102600D01*
X268100Y-103533D01*
X267500Y-104333D01*
X266800Y-104867D01*
X266000Y-105000D01*
G01X272000D02*
Y-97000D01*
X274400D01*
X275200Y-97400D01*
X275800Y-98333D01*
X276000Y-99400D01*
X275800Y-100467D01*
X275300Y-101267D01*
X274400Y-101667D01*
X272000D01*
G01X202000Y-72000D02*
Y-80000D01*
X206000D01*
G01X213800D02*
Y-74667D01*
G01Y-75600D02*
X213400Y-75067D01*
X212800Y-74800D01*
X212100Y-74667D01*
X211400Y-74933D01*
X210800Y-75467D01*
X210400Y-76267D01*
X210200Y-77333D01*
X210400Y-78400D01*
X210800Y-79200D01*
X211400Y-79733D01*
X212100Y-80000D01*
X212800Y-79867D01*
X213400Y-79467D01*
X213800Y-78934D01*
G01X217900Y-82400D02*
X218500Y-82667D01*
X219300Y-82400D01*
X219800Y-81867D01*
X220200Y-81200D01*
X220800Y-79067D01*
X222100Y-74667D01*
G01X218900D02*
X220800Y-79067D01*
G01X226500Y-76400D02*
X229700D01*
X229400Y-75467D01*
X228900Y-74933D01*
X228200Y-74667D01*
X227500Y-74800D01*
X226900Y-75200D01*
X226500Y-76133D01*
X226300Y-76934D01*
Y-77733D01*
X226500Y-78533D01*
X227000Y-79333D01*
X227600Y-79867D01*
X228300Y-80000D01*
X229000Y-79733D01*
X229700Y-78934D01*
G01X234600Y-80000D02*
Y-74667D01*
G01Y-75733D02*
X235100Y-75200D01*
X235600Y-74800D01*
X236300Y-74667D01*
X236800Y-74800D01*
X237400Y-75200D01*
G01X223400Y-128934D02*
X224200Y-129600D01*
X225100Y-130000D01*
X225900D01*
X226700Y-129600D01*
X227300Y-128934D01*
X227600Y-128000D01*
X227400Y-127067D01*
X226900Y-126267D01*
X226000Y-125733D01*
X224800Y-125467D01*
X224100Y-124933D01*
X223800Y-124000D01*
X224000Y-123067D01*
X224500Y-122400D01*
X225200Y-122000D01*
X225900D01*
X226600Y-122267D01*
X227200Y-122933D01*
G01X235300Y-130000D02*
Y-124667D01*
G01Y-125600D02*
X234900Y-125067D01*
X234300Y-124800D01*
X233600Y-124667D01*
X232900Y-124933D01*
X232300Y-125467D01*
X231900Y-126267D01*
X231700Y-127333D01*
X231900Y-128400D01*
X232300Y-129200D01*
X232900Y-129733D01*
X233600Y-130000D01*
X234300Y-129867D01*
X234900Y-129467D01*
X235300Y-128934D01*
G01X239800Y-130000D02*
Y-124667D01*
G01Y-126000D02*
X240200Y-125333D01*
X240800Y-124800D01*
X241600Y-124667D01*
X242300Y-124800D01*
X242900Y-125333D01*
X243200Y-126267D01*
Y-130000D01*
G01X251300Y-122000D02*
Y-130000D01*
G01Y-128800D02*
X250900Y-129467D01*
X250300Y-129867D01*
X249600Y-130000D01*
X248800Y-129733D01*
X248200Y-129067D01*
X247800Y-128267D01*
X247700Y-127333D01*
X247800Y-126400D01*
X248200Y-125600D01*
X248800Y-124933D01*
X249600Y-124667D01*
X250300Y-124800D01*
X250800Y-125067D01*
X251300Y-125600D01*
G01X255400Y-132400D02*
X256000Y-132667D01*
X256800Y-132400D01*
X257300Y-131867D01*
X257700Y-131200D01*
X258300Y-129067D01*
X259600Y-124667D01*
G01X256400D02*
X258300Y-129067D01*
G01X328600Y-123333D02*
X329200Y-122533D01*
X329900Y-122133D01*
X330700Y-122000D01*
X331700Y-122267D01*
X332400Y-122933D01*
X332600Y-123733D01*
X332500Y-124534D01*
X332100Y-125200D01*
X330100Y-126533D01*
X329200Y-127467D01*
X328600Y-128800D01*
X328400Y-130000D01*
X332600D01*
G01X338500Y-122000D02*
X337700Y-122267D01*
X337100Y-122933D01*
X336700Y-123733D01*
X336400Y-124800D01*
X336300Y-126000D01*
X336400Y-127200D01*
X336700Y-128267D01*
X337100Y-129067D01*
X337700Y-129733D01*
X338500Y-130000D01*
X339300Y-129733D01*
X339900Y-129067D01*
X340300Y-128267D01*
X340600Y-127200D01*
X340700Y-126000D01*
X340600Y-124800D01*
X340300Y-123733D01*
X339900Y-122933D01*
X339300Y-122267D01*
X338500Y-122000D01*
G01X346500Y-130000D02*
Y-122000D01*
X345300Y-123600D01*
G01Y-130000D02*
X347700D01*
G01X352600Y-123333D02*
X353200Y-122533D01*
X353900Y-122133D01*
X354700Y-122000D01*
X355700Y-122267D01*
X356400Y-122933D01*
X356600Y-123733D01*
X356500Y-124534D01*
X356100Y-125200D01*
X354100Y-126533D01*
X353200Y-127467D01*
X352600Y-128800D01*
X352400Y-130000D01*
X356600D01*
G01X360700Y-130267D02*
X364300Y-122000D01*
G01X370500D02*
X369700Y-122267D01*
X369100Y-122933D01*
X368700Y-123733D01*
X368400Y-124800D01*
X368300Y-126000D01*
X368400Y-127200D01*
X368700Y-128267D01*
X369100Y-129067D01*
X369700Y-129733D01*
X370500Y-130000D01*
X371300Y-129733D01*
X371900Y-129067D01*
X372300Y-128267D01*
X372600Y-127200D01*
X372700Y-126000D01*
X372600Y-124800D01*
X372300Y-123733D01*
X371900Y-122933D01*
X371300Y-122267D01*
X370500Y-122000D01*
G01X376800Y-129067D02*
X377500Y-129733D01*
X378300Y-130000D01*
X379100Y-129733D01*
X379800Y-128934D01*
X380300Y-127733D01*
X380500Y-126533D01*
Y-125067D01*
X380300Y-123867D01*
X379800Y-122800D01*
X379200Y-122267D01*
X378500Y-122000D01*
X377700Y-122267D01*
X377100Y-122800D01*
X376700Y-123600D01*
X376500Y-124667D01*
X376700Y-125600D01*
X377200Y-126533D01*
X377800Y-127067D01*
X378500Y-127200D01*
X379300Y-126934D01*
X379900Y-126267D01*
X380500Y-125067D01*
G01X384700Y-130267D02*
X388300Y-122000D01*
G01X392600Y-123333D02*
X393200Y-122533D01*
X393900Y-122133D01*
X394700Y-122000D01*
X395700Y-122267D01*
X396400Y-122933D01*
X396600Y-123733D01*
X396500Y-124534D01*
X396100Y-125200D01*
X394100Y-126533D01*
X393200Y-127467D01*
X392600Y-128800D01*
X392400Y-130000D01*
X396600D01*
G01X402500D02*
X403200Y-129867D01*
X404000Y-129467D01*
X404500Y-128800D01*
X404700Y-127867D01*
X404500Y-126934D01*
X403900Y-126133D01*
X403000Y-125733D01*
X402000D01*
X401400Y-125467D01*
X400900Y-124800D01*
X400700Y-123867D01*
X401000Y-122933D01*
X401700Y-122267D01*
X402500Y-122000D01*
X403300Y-122267D01*
X404000Y-122933D01*
X404300Y-123867D01*
X404100Y-124800D01*
X403600Y-125467D01*
X403000Y-125733D01*
X402000D01*
X401100Y-126133D01*
X400500Y-126934D01*
X400300Y-127867D01*
X400500Y-128800D01*
X401000Y-129467D01*
X401800Y-129867D01*
X402500Y-130000D01*
G01X328300Y-105000D02*
Y-97000D01*
X330300D01*
X331100Y-97400D01*
X331700Y-97933D01*
X332200Y-98733D01*
X332600Y-99667D01*
X332700Y-101000D01*
X332600Y-102333D01*
X332200Y-103267D01*
X331700Y-104067D01*
X331100Y-104600D01*
X330300Y-105000D01*
X328300D01*
G01X336000D02*
X338500Y-97000D01*
X341000Y-105000D01*
G01X340100Y-102200D02*
X336900D01*
G01X346500Y-97000D02*
X345700Y-97267D01*
X345100Y-97933D01*
X344700Y-98733D01*
X344400Y-99800D01*
X344300Y-101000D01*
X344400Y-102200D01*
X344700Y-103267D01*
X345100Y-104067D01*
X345700Y-104733D01*
X346500Y-105000D01*
X347300Y-104733D01*
X347900Y-104067D01*
X348300Y-103267D01*
X348600Y-102200D01*
X348700Y-101000D01*
X348600Y-99800D01*
X348300Y-98733D01*
X347900Y-97933D01*
X347300Y-97267D01*
X346500Y-97000D01*
G01X354500D02*
Y-105000D01*
G01X352200Y-97000D02*
X356800D01*
G01X360600Y-101667D02*
X361300Y-100733D01*
X361900Y-100200D01*
X362700Y-99933D01*
X363400Y-100200D01*
X363900Y-100733D01*
X364300Y-101533D01*
X364400Y-102467D01*
X364300Y-103267D01*
X363900Y-104067D01*
X363300Y-104733D01*
X362600Y-105000D01*
X361800Y-104733D01*
X361100Y-103934D01*
X360700Y-102733D01*
X360600Y-101400D01*
X360800Y-99667D01*
X361100Y-98733D01*
X361600Y-97800D01*
X362300Y-97133D01*
X363000Y-97000D01*
X363700Y-97267D01*
X364200Y-97933D01*
G01X367900Y-105000D02*
Y-97000D01*
X370500Y-103667D01*
X373100Y-97000D01*
Y-105000D01*
G01X378500Y-97000D02*
Y-105000D01*
G01X376200Y-97000D02*
X380800D01*
G01X387300Y-100733D02*
X387700Y-100333D01*
X388000Y-99667D01*
X388200Y-98733D01*
X388000Y-97933D01*
X387600Y-97400D01*
X386900Y-97000D01*
X384200D01*
Y-105000D01*
X387500D01*
X388200Y-104467D01*
X388600Y-103667D01*
X388800Y-102733D01*
X388600Y-101800D01*
X388000Y-101000D01*
X387300Y-100733D01*
X384200D01*
G01X394500Y-105000D02*
X395200Y-104867D01*
X396000Y-104467D01*
X396500Y-103800D01*
X396700Y-102867D01*
X396500Y-101934D01*
X395900Y-101133D01*
X395000Y-100733D01*
X394000D01*
X393400Y-100467D01*
X392900Y-99800D01*
X392700Y-98867D01*
X393000Y-97933D01*
X393700Y-97267D01*
X394500Y-97000D01*
X395300Y-97267D01*
X396000Y-97933D01*
X396300Y-98867D01*
X396100Y-99800D01*
X395600Y-100467D01*
X395000Y-100733D01*
X394000D01*
X393100Y-101133D01*
X392500Y-101934D01*
X392300Y-102867D01*
X392500Y-103800D01*
X393000Y-104467D01*
X393800Y-104867D01*
X394500Y-105000D01*
G01X400300D02*
Y-97000D01*
X402300D01*
X403100Y-97400D01*
X403700Y-97933D01*
X404200Y-98733D01*
X404600Y-99667D01*
X404700Y-101000D01*
X404600Y-102333D01*
X404200Y-103267D01*
X403700Y-104067D01*
X403100Y-104600D01*
X402300Y-105000D01*
X400300D01*
G01X410500Y-97000D02*
X409700Y-97267D01*
X409100Y-97933D01*
X408700Y-98733D01*
X408400Y-99800D01*
X408300Y-101000D01*
X408400Y-102200D01*
X408700Y-103267D01*
X409100Y-104067D01*
X409700Y-104733D01*
X410500Y-105000D01*
X411300Y-104733D01*
X411900Y-104067D01*
X412300Y-103267D01*
X412600Y-102200D01*
X412700Y-101000D01*
X412600Y-99800D01*
X412300Y-98733D01*
X411900Y-97933D01*
X411300Y-97267D01*
X410500Y-97000D01*
G01X350500Y-72000D02*
Y-80000D01*
G01X348200Y-72000D02*
X352800D01*
G01X356600Y-76667D02*
X357300Y-75733D01*
X357900Y-75200D01*
X358700Y-74933D01*
X359400Y-75200D01*
X359900Y-75733D01*
X360300Y-76533D01*
X360400Y-77467D01*
X360300Y-78267D01*
X359900Y-79067D01*
X359300Y-79733D01*
X358600Y-80000D01*
X357800Y-79733D01*
X357100Y-78934D01*
X356700Y-77733D01*
X356600Y-76400D01*
X356800Y-74667D01*
X357100Y-73733D01*
X357600Y-72800D01*
X358300Y-72133D01*
X359000Y-72000D01*
X359700Y-72267D01*
X360200Y-72933D01*
G01X363900Y-80000D02*
Y-72000D01*
X366500Y-78667D01*
X369100Y-72000D01*
Y-80000D01*
G01X371500Y-82667D02*
X377500D01*
G01X380500Y-80000D02*
Y-72000D01*
X382900D01*
X383700Y-72400D01*
X384300Y-73333D01*
X384500Y-74400D01*
X384300Y-75467D01*
X383800Y-76267D01*
X382900Y-76667D01*
X380500D01*
G01X388300Y-80000D02*
Y-72000D01*
X390300D01*
X391100Y-72400D01*
X391700Y-72933D01*
X392200Y-73733D01*
X392600Y-74667D01*
X392700Y-76000D01*
X392600Y-77333D01*
X392200Y-78267D01*
X391700Y-79067D01*
X391100Y-79600D01*
X390300Y-80000D01*
X388300D01*
G01X399300Y-75733D02*
X399700Y-75333D01*
X400000Y-74667D01*
X400200Y-73733D01*
X400000Y-72933D01*
X399600Y-72400D01*
X398900Y-72000D01*
X396200D01*
Y-80000D01*
X399500D01*
X400200Y-79467D01*
X400600Y-78667D01*
X400800Y-77733D01*
X400600Y-76800D01*
X400000Y-76000D01*
X399300Y-75733D01*
X396200D01*
G01X403500Y-82667D02*
X409500D01*
G01X412300Y-80000D02*
Y-72000D01*
X414300D01*
X415100Y-72400D01*
X415700Y-72933D01*
X416200Y-73733D01*
X416600Y-74667D01*
X416700Y-76000D01*
X416600Y-77333D01*
X416200Y-78267D01*
X415700Y-79067D01*
X415100Y-79600D01*
X414300Y-80000D01*
X412300D01*
G01X419500Y-82667D02*
X425500D01*
G01X431300Y-75733D02*
X431700Y-75333D01*
X432000Y-74667D01*
X432200Y-73733D01*
X432000Y-72933D01*
X431600Y-72400D01*
X430900Y-72000D01*
X428200D01*
Y-80000D01*
X431500D01*
X432200Y-79467D01*
X432600Y-78667D01*
X432800Y-77733D01*
X432600Y-76800D01*
X432000Y-76000D01*
X431300Y-75733D01*
X428200D01*
G01X436300Y-80000D02*
Y-72000D01*
X438300D01*
X439100Y-72400D01*
X439700Y-72933D01*
X440200Y-73733D01*
X440600Y-74667D01*
X440700Y-76000D01*
X440600Y-77333D01*
X440200Y-78267D01*
X439700Y-79067D01*
X439100Y-79600D01*
X438300Y-80000D01*
X436300D01*
G01X443300Y-130000D02*
Y-122000D01*
X445300D01*
X446100Y-122400D01*
X446700Y-122933D01*
X447200Y-123733D01*
X447600Y-124667D01*
X447700Y-126000D01*
X447600Y-127333D01*
X447200Y-128267D01*
X446700Y-129067D01*
X446100Y-129600D01*
X445300Y-130000D01*
X443300D01*
G01X473000D02*
Y-122000D01*
X471800Y-123600D01*
G01Y-130000D02*
X474200D01*
G01X478800Y-128800D02*
X479400Y-129467D01*
X480100Y-129867D01*
X481000Y-130000D01*
X481900Y-129733D01*
X482600Y-129200D01*
X483100Y-128267D01*
X483200Y-127200D01*
X483000Y-126133D01*
X482500Y-125467D01*
X481800Y-124933D01*
X481100Y-124800D01*
X480400Y-124933D01*
X479500Y-125467D01*
X479800Y-122000D01*
X482500D01*
G54D31*
X119920Y328071D03*
Y676102D03*
Y1024134D03*
Y1372165D03*
Y1720197D03*
Y2068228D03*
G54D22*
X18995Y1612992D03*
X53995Y518701D03*
G54D13*
X18995Y508701D03*
X23995Y518701D03*
X21495Y559882D03*
X11692D03*
X21495Y1571811D03*
X11692D03*
X23995Y1622992D03*
X28995Y508701D03*
X38995D03*
X48995D03*
X33995Y518701D03*
X43995D03*
X51495Y559882D03*
Y1571811D03*
X43995Y1622992D03*
X33995D03*
X48995Y1612992D03*
X38995D03*
X28995D03*
X61298Y559882D03*
Y1571811D03*
X53995Y1622992D03*
G54D14*
X13995Y543701D03*
Y1587992D03*
X58995Y543701D03*
Y1587992D03*
G54D32*
X163385Y27205D03*
Y202205D03*
Y377205D03*
X163386Y552205D03*
Y727205D03*
X163385Y902205D03*
Y1077205D03*
Y1252205D03*
Y1427205D03*
Y1602205D03*
Y1777205D03*
Y1952205D03*
X373385Y32520D03*
Y207520D03*
Y382520D03*
X373386Y557520D03*
Y732520D03*
X373385Y907520D03*
Y1082520D03*
Y1257520D03*
Y1432520D03*
Y1607520D03*
Y1782520D03*
Y1957520D03*
G54D23*
X23402Y1668874D03*
Y1685410D03*
Y1701945D03*
Y1718480D03*
Y1735016D03*
Y1751551D03*
Y1768087D03*
Y1784622D03*
Y1817693D03*
Y1801158D03*
X45056Y1668874D03*
Y1685410D03*
Y1701945D03*
Y1718480D03*
Y1735016D03*
Y1751551D03*
Y1768087D03*
Y1784622D03*
Y1801158D03*
G54D15*
X5491Y528544D03*
Y1603149D03*
X67499Y528544D03*
Y1603149D03*
G54D24*
X45056Y1817693D03*
G54D33*
X173385Y32520D03*
Y207520D03*
Y382520D03*
X173386Y557520D03*
Y732520D03*
X173385Y907520D03*
Y1082520D03*
Y1257520D03*
Y1432520D03*
Y1607520D03*
Y1782520D03*
Y1957520D03*
G54D16*
X11677Y572812D03*
Y575962D03*
X16484Y1555159D03*
Y1558309D03*
X11085Y1555291D03*
Y1558441D03*
X58750Y577016D03*
Y573866D03*
X63820Y577082D03*
Y573932D03*
X58752Y1302746D03*
Y1299596D03*
X71909Y1302580D03*
Y1299430D03*
X50331Y1302680D03*
Y1299530D03*
X54543Y1302681D03*
Y1299531D03*
X63061Y1302746D03*
Y1299596D03*
X67568Y1302581D03*
Y1299431D03*
X52958Y1336081D03*
Y1339231D03*
X107268Y78205D03*
X107263Y75055D03*
Y78205D03*
X107268Y81355D03*
X107668Y429254D03*
Y426104D03*
Y422954D03*
Y426104D03*
X107615Y777299D03*
Y774149D03*
X107617Y771001D03*
Y774151D03*
X108819Y1119015D03*
X108816Y1125313D03*
Y1122163D03*
X108819Y1122165D03*
X108573Y1473357D03*
Y1470207D03*
X108574Y1467057D03*
Y1470207D03*
X108819Y1818228D03*
Y1815078D03*
Y1818228D03*
Y1821378D03*
X155370Y91281D03*
Y88131D03*
X155366Y85017D03*
Y88167D03*
X156321Y418198D03*
Y415048D03*
X161256Y418195D03*
Y415045D03*
X155351Y439268D03*
Y436118D03*
X155348Y432969D03*
Y436119D03*
X155356Y780982D03*
X155362Y787280D03*
Y784130D03*
X155356Y784132D03*
X156117Y1116127D03*
Y1112977D03*
X160870Y1116135D03*
Y1112985D03*
X155264Y1135344D03*
Y1132194D03*
X155263Y1129045D03*
Y1132195D03*
X155834Y1480274D03*
X155816Y1477124D03*
Y1480274D03*
X155834Y1483424D03*
X155570Y1831380D03*
Y1828230D03*
X155561Y1825087D03*
Y1828237D03*
X283086Y166264D03*
Y169414D03*
X287420Y166264D03*
Y169414D03*
X276617Y238439D03*
Y235289D03*
X281193Y238439D03*
Y235289D03*
X281074Y341517D03*
Y344667D03*
X289895Y341517D03*
Y344667D03*
X285513Y341517D03*
Y344667D03*
X291002Y414015D03*
Y410865D03*
X286665Y414015D03*
Y410865D03*
X278405Y515919D03*
Y519069D03*
X273938Y515919D03*
Y519069D03*
X282776Y515919D03*
Y519069D03*
X269516Y515919D03*
Y519069D03*
X290984Y585487D03*
Y588637D03*
X283340Y691124D03*
Y694274D03*
X278955Y691124D03*
Y694274D03*
X274514Y691124D03*
Y694274D03*
X270109Y691124D03*
Y694274D03*
X278184Y763711D03*
Y760561D03*
X282737Y763711D03*
Y760561D03*
X285788Y866243D03*
Y869393D03*
X281305Y866243D03*
Y869393D03*
X276686Y866243D03*
Y869393D03*
X272181Y866243D03*
Y869393D03*
X281194Y937436D03*
Y934286D03*
X285874Y937436D03*
Y934286D03*
X290107Y1034882D03*
Y1038032D03*
X285666Y1034882D03*
Y1038032D03*
X281124Y1034882D03*
Y1038032D03*
X288188Y1112426D03*
Y1109276D03*
X284194Y1210314D03*
Y1213464D03*
X289082Y1210314D03*
Y1213464D03*
X279559Y1210314D03*
Y1213464D03*
X289210Y1287097D03*
Y1283947D03*
X284240Y1393342D03*
Y1396492D03*
X279518Y1393341D03*
Y1396491D03*
X275052Y1393341D03*
Y1396491D03*
X270579Y1393341D03*
Y1396491D03*
X275521Y1457487D03*
X279990D03*
X275521Y1460637D03*
X279990D03*
X289675Y1562451D03*
Y1565601D03*
X285054Y1562451D03*
Y1565601D03*
X289421Y1637318D03*
Y1634168D03*
X289499Y1741915D03*
Y1745065D03*
X284583Y1741915D03*
Y1745065D03*
X274704Y1741915D03*
Y1745065D03*
X279703Y1741915D03*
Y1745065D03*
X286623Y1811546D03*
Y1808396D03*
X291550Y1811546D03*
Y1808396D03*
X287121Y1916895D03*
Y1920045D03*
X282717Y1916895D03*
Y1920045D03*
X278262Y1916895D03*
Y1920045D03*
X273817Y1916895D03*
Y1920045D03*
X304151Y60393D03*
Y57243D03*
X308651Y60393D03*
Y57243D03*
X313089Y60393D03*
Y57243D03*
X299687Y60393D03*
Y57243D03*
X291943Y166264D03*
Y169414D03*
X296523Y166264D03*
Y169414D03*
X294506Y341517D03*
Y344667D03*
X295509Y585487D03*
Y588637D03*
X294617Y1034882D03*
Y1038032D03*
X292698Y1112426D03*
Y1109276D03*
X293807Y1210314D03*
Y1213464D03*
X294133Y1287097D03*
Y1283947D03*
X298870Y1562451D03*
Y1565601D03*
X294392Y1562451D03*
Y1565601D03*
X294090Y1637318D03*
Y1634168D03*
X317567Y60393D03*
Y57243D03*
X322005Y60393D03*
Y57243D03*
X320045Y1987031D03*
Y1983881D03*
X324803Y1987031D03*
Y1983881D03*
G54D25*
X65354Y101180D03*
X55511Y105117D03*
X51574Y114960D03*
X55511Y124803D03*
X65354Y128740D03*
Y451180D03*
X55511Y455117D03*
X51574Y464960D03*
X55511Y474803D03*
X65354Y478740D03*
Y801180D03*
X55511Y805117D03*
X51574Y814960D03*
X55511Y824803D03*
X65354Y828740D03*
Y1151180D03*
X55511Y1155117D03*
X51574Y1164960D03*
X55511Y1174803D03*
X65354Y1178740D03*
Y1501180D03*
X55511Y1505117D03*
X51574Y1514960D03*
X55511Y1524803D03*
X65354Y1528740D03*
Y1851180D03*
X55511Y1855117D03*
X51574Y1864960D03*
X55511Y1874803D03*
X65354Y1878740D03*
X75197Y105117D03*
Y124803D03*
X79134Y114960D03*
Y464960D03*
X75197Y455117D03*
Y474803D03*
Y805117D03*
Y824803D03*
X79134Y814960D03*
Y1164960D03*
X75197Y1155117D03*
Y1174803D03*
Y1505117D03*
Y1524803D03*
X79134Y1514960D03*
Y1864960D03*
X75197Y1855117D03*
Y1874803D03*
X307086Y113385D03*
X297243Y117322D03*
X293306Y127165D03*
X297243Y137008D03*
X307086Y140945D03*
Y463385D03*
X297243Y467322D03*
X293306Y477165D03*
X297243Y487008D03*
X307086Y490945D03*
Y813385D03*
X297243Y817322D03*
X293306Y827165D03*
X297243Y837008D03*
X307086Y840945D03*
Y1329724D03*
X297243Y1333661D03*
X293306Y1343504D03*
X297243Y1353347D03*
X307086Y1357284D03*
Y1679724D03*
X297243Y1683661D03*
X293306Y1693504D03*
X297243Y1703347D03*
X307086Y1707284D03*
X307087Y2029723D03*
X297244Y2033660D03*
X293307Y2043503D03*
X297244Y2053346D03*
X307087Y2057283D03*
X320866Y127165D03*
X316929Y117322D03*
Y137008D03*
Y467322D03*
Y487008D03*
X320866Y477165D03*
Y827165D03*
X316929Y817322D03*
Y837008D03*
Y1333661D03*
Y1353347D03*
X320866Y1343504D03*
Y1693504D03*
X316929Y1683661D03*
Y1703347D03*
X316930Y2033660D03*
Y2053346D03*
X320867Y2043503D03*
G54D34*
X173385Y21890D03*
X183385Y32520D03*
Y21890D03*
X193385Y32520D03*
Y21890D03*
X173385Y196890D03*
X183385D03*
X193385D03*
X183385Y207520D03*
X193385D03*
X173385Y371890D03*
X183385D03*
X193385D03*
X183385Y382520D03*
X193385D03*
X173386Y546890D03*
X183386Y557520D03*
Y546890D03*
X193386Y557520D03*
Y546890D03*
X173386Y721890D03*
X183386Y732520D03*
Y721890D03*
X193386Y732520D03*
Y721890D03*
X173385Y896890D03*
X183385D03*
X193385D03*
X183385Y907520D03*
X193385D03*
X173385Y1071890D03*
X183385D03*
X193385D03*
X183385Y1082520D03*
X193385D03*
X173385Y1246890D03*
X183385Y1257520D03*
Y1246890D03*
X193385Y1257520D03*
Y1246890D03*
X173385Y1421890D03*
X183385Y1432520D03*
Y1421890D03*
X193385Y1432520D03*
Y1421890D03*
X173385Y1596890D03*
X183385D03*
X193385D03*
X183385Y1607520D03*
X193385D03*
X173385Y1771890D03*
X183385D03*
X193385D03*
X183385Y1782520D03*
X193385D03*
X173385Y1946890D03*
X183385Y1957520D03*
Y1946890D03*
X193385Y1957520D03*
Y1946890D03*
X203385Y32520D03*
Y21890D03*
X213385Y32520D03*
Y21890D03*
X203385Y196890D03*
X213385D03*
X203385Y207520D03*
X213385D03*
X203385Y371890D03*
X213385D03*
X203385Y382520D03*
X213385D03*
X203386Y557520D03*
Y546890D03*
X213386Y557520D03*
Y546890D03*
X203386Y732520D03*
Y721890D03*
X213386Y732520D03*
Y721890D03*
X203385Y896890D03*
X213385D03*
X203385Y907520D03*
X213385D03*
X203385Y1071890D03*
X213385D03*
X203385Y1082520D03*
X213385D03*
X203385Y1257520D03*
Y1246890D03*
X213385Y1257520D03*
Y1246890D03*
X203385Y1432520D03*
Y1421890D03*
X213385Y1432520D03*
Y1421890D03*
X203385Y1596890D03*
X213385D03*
X203385Y1607520D03*
X213385D03*
X203385Y1771890D03*
X213385D03*
X203385Y1782520D03*
X213385D03*
X203385Y1957520D03*
Y1946890D03*
X213385Y1957520D03*
Y1946890D03*
X223385Y32520D03*
Y21890D03*
X233385Y32520D03*
Y21890D03*
X243385Y32520D03*
Y21890D03*
X223385Y196890D03*
X233385D03*
X243385D03*
X223385Y207520D03*
X233385D03*
X243385D03*
X223385Y371890D03*
X233385D03*
X243385D03*
X223385Y382520D03*
X233385D03*
X243385D03*
X223386Y557520D03*
Y546890D03*
X233386Y557520D03*
Y546890D03*
X243386Y557520D03*
Y546890D03*
X223386Y732520D03*
Y721890D03*
X233386Y732520D03*
Y721890D03*
X243386Y732520D03*
Y721890D03*
X223385Y896890D03*
X233385D03*
X243385D03*
X223385Y907520D03*
X233385D03*
X243385D03*
X223385Y1071890D03*
X233385D03*
X243385D03*
X223385Y1082520D03*
X233385D03*
X243385D03*
X223385Y1257520D03*
Y1246890D03*
X233385Y1257520D03*
Y1246890D03*
X243385Y1257520D03*
Y1246890D03*
X223385Y1432520D03*
Y1421890D03*
X233385Y1432520D03*
Y1421890D03*
X243385Y1432520D03*
Y1421890D03*
X223385Y1596890D03*
X233385D03*
X243385D03*
X223385Y1607520D03*
X233385D03*
X243385D03*
X223385Y1771890D03*
X233385D03*
X243385D03*
X223385Y1782520D03*
X233385D03*
X243385D03*
X223385Y1957520D03*
Y1946890D03*
X233385Y1957520D03*
Y1946890D03*
X243385Y1957520D03*
Y1946890D03*
X253385Y21890D03*
Y32520D03*
X263385Y21890D03*
Y32520D03*
X253385Y196890D03*
X263385D03*
X253385Y207520D03*
X263385D03*
X253385Y371890D03*
X263385D03*
X253385Y382520D03*
X263385D03*
X253386Y546890D03*
Y557520D03*
X263386Y546890D03*
Y557520D03*
X253386Y721890D03*
Y732520D03*
X263386Y721890D03*
Y732520D03*
X253385Y896890D03*
X263385D03*
X253385Y907520D03*
X263385D03*
X253385Y1071890D03*
X263385D03*
X253385Y1082520D03*
X263385D03*
X253385Y1246890D03*
Y1257520D03*
X263385Y1246890D03*
Y1257520D03*
X253385Y1421890D03*
Y1432520D03*
X263385Y1421890D03*
Y1432520D03*
X253385Y1596890D03*
X263385D03*
X253385Y1607520D03*
X263385D03*
X253385Y1771890D03*
X263385D03*
X253385Y1782520D03*
X263385D03*
X253385Y1946890D03*
Y1957520D03*
X263385Y1946890D03*
Y1957520D03*
X273385Y21890D03*
Y32520D03*
X283385Y21890D03*
Y32520D03*
X273385Y196890D03*
X283385D03*
X273385Y207520D03*
X283385D03*
X273385Y371890D03*
X283385D03*
X273385Y382520D03*
X283385D03*
X273386Y546890D03*
Y557520D03*
X283386Y546890D03*
Y557520D03*
X273386Y721890D03*
Y732520D03*
X283386Y721890D03*
Y732520D03*
X273385Y896890D03*
X283385D03*
X273385Y907520D03*
X283385D03*
X273385Y1071890D03*
X283385D03*
X273385Y1082520D03*
X283385D03*
X273385Y1246890D03*
Y1257520D03*
X283385Y1246890D03*
Y1257520D03*
X273385Y1421890D03*
Y1432520D03*
X283385Y1421890D03*
Y1432520D03*
X273385Y1596890D03*
X283385D03*
X273385Y1607520D03*
X283385D03*
X273385Y1771890D03*
X283385D03*
X273385Y1782520D03*
X283385D03*
X273385Y1946890D03*
Y1957520D03*
X283385Y1946890D03*
Y1957520D03*
X293385Y21890D03*
Y32520D03*
X303385Y21890D03*
Y32520D03*
X313385D03*
Y21890D03*
X293385Y196890D03*
X303385D03*
X313385D03*
X293385Y207520D03*
X303385D03*
X313385D03*
X293385Y371890D03*
X303385D03*
X313385D03*
X293385Y382520D03*
X303385D03*
X313385D03*
X293386Y546890D03*
Y557520D03*
X303386Y546890D03*
Y557520D03*
X313386D03*
Y546890D03*
X293386Y721890D03*
Y732520D03*
X303386Y721890D03*
Y732520D03*
X313386D03*
Y721890D03*
X293385Y896890D03*
X303385D03*
X313385D03*
X293385Y907520D03*
X303385D03*
X313385D03*
X293385Y1071890D03*
X303385D03*
X313385D03*
X293385Y1082520D03*
X303385D03*
X313385D03*
X293385Y1246890D03*
Y1257520D03*
X303385Y1246890D03*
Y1257520D03*
X313385D03*
Y1246890D03*
X293385Y1421890D03*
Y1432520D03*
X303385Y1421890D03*
Y1432520D03*
X313385D03*
Y1421890D03*
X293385Y1596890D03*
X303385D03*
X313385D03*
X293385Y1607520D03*
X303385D03*
X313385D03*
X293385Y1771890D03*
X303385D03*
X313385D03*
X293385Y1782520D03*
X303385D03*
X313385D03*
X293385Y1946890D03*
Y1957520D03*
X303385Y1946890D03*
Y1957520D03*
X313385D03*
Y1946890D03*
X337165Y24705D03*
X323385Y32520D03*
Y21890D03*
X337165Y34705D03*
Y199705D03*
X323385Y196890D03*
X337165Y209705D03*
X323385Y207520D03*
Y371890D03*
X337165Y374705D03*
Y384705D03*
X323385Y382520D03*
X337166Y549705D03*
Y559705D03*
X323386Y557520D03*
Y546890D03*
X337166Y724705D03*
X323386Y732520D03*
Y721890D03*
X337166Y734705D03*
X337165Y899705D03*
X323385Y896890D03*
X337165Y909705D03*
X323385Y907520D03*
Y1071890D03*
X337165Y1074705D03*
Y1084705D03*
X323385Y1082520D03*
X337165Y1249705D03*
Y1259705D03*
X323385Y1257520D03*
Y1246890D03*
X337165Y1424705D03*
Y1434705D03*
X323385Y1432520D03*
Y1421890D03*
X337165Y1599705D03*
X323385Y1596890D03*
X337165Y1609705D03*
X323385Y1607520D03*
Y1771890D03*
X337165Y1774705D03*
Y1784705D03*
X323385Y1782520D03*
X337165Y1949705D03*
Y1959705D03*
X323385Y1957520D03*
Y1946890D03*
X342165Y19705D03*
Y29705D03*
X347165Y24705D03*
X352165Y19705D03*
Y29705D03*
X357165Y24705D03*
X362165Y19705D03*
Y29705D03*
X347165Y34705D03*
X357165D03*
X342165Y194705D03*
X347165Y199705D03*
X352165Y194705D03*
X357165Y199705D03*
X362165Y194705D03*
X342165Y204705D03*
X347165Y209705D03*
X352165Y204705D03*
X357165Y209705D03*
X362165Y204705D03*
X342165Y369705D03*
X352165D03*
X362165D03*
X342165Y379705D03*
X347165Y374705D03*
Y384705D03*
X352165Y379705D03*
X357165Y374705D03*
Y384705D03*
X362165Y379705D03*
X342166Y544705D03*
Y554705D03*
X347166Y549705D03*
Y559705D03*
X352166Y544705D03*
Y554705D03*
X357166Y549705D03*
Y559705D03*
X362166Y544705D03*
Y554705D03*
X342166Y719705D03*
Y729705D03*
X347166Y724705D03*
X352166Y719705D03*
Y729705D03*
X357166Y724705D03*
X362166Y719705D03*
Y729705D03*
X347166Y734705D03*
X357166D03*
X342165Y894705D03*
X347165Y899705D03*
X352165Y894705D03*
X357165Y899705D03*
X362165Y894705D03*
X342165Y904705D03*
X347165Y909705D03*
X352165Y904705D03*
X357165Y909705D03*
X362165Y904705D03*
X342165Y1069705D03*
X352165D03*
X362165D03*
X342165Y1079705D03*
X347165Y1074705D03*
Y1084705D03*
X352165Y1079705D03*
X357165Y1074705D03*
Y1084705D03*
X362165Y1079705D03*
X342165Y1244705D03*
Y1254705D03*
X347165Y1249705D03*
Y1259705D03*
X352165Y1244705D03*
Y1254705D03*
X357165Y1249705D03*
Y1259705D03*
X362165Y1244705D03*
Y1254705D03*
X342165Y1419705D03*
Y1429705D03*
X347165Y1424705D03*
Y1434705D03*
X352165Y1419705D03*
Y1429705D03*
X357165Y1424705D03*
Y1434705D03*
X362165Y1419705D03*
Y1429705D03*
X342165Y1594705D03*
X347165Y1599705D03*
X352165Y1594705D03*
X357165Y1599705D03*
X362165Y1594705D03*
X342165Y1604705D03*
X347165Y1609705D03*
X352165Y1604705D03*
X357165Y1609705D03*
X362165Y1604705D03*
X342165Y1769705D03*
X352165D03*
X362165D03*
X342165Y1779705D03*
X347165Y1774705D03*
Y1784705D03*
X352165Y1779705D03*
X357165Y1774705D03*
Y1784705D03*
X362165Y1779705D03*
X342165Y1944705D03*
Y1954705D03*
X347165Y1949705D03*
Y1959705D03*
X352165Y1944705D03*
Y1954705D03*
X357165Y1949705D03*
Y1959705D03*
X362165Y1944705D03*
Y1954705D03*
G54D26*
X65354Y114960D03*
Y464960D03*
Y814960D03*
Y1164960D03*
Y1514960D03*
Y1864960D03*
X307086Y127165D03*
Y477165D03*
Y827165D03*
Y1343504D03*
Y1693504D03*
X307087Y2043503D03*
G54D35*
X271547Y235964D03*
Y241764D03*
X281569Y411540D03*
Y417340D03*
X285348Y586162D03*
Y591962D03*
X273114Y761236D03*
Y767036D03*
X275966Y934961D03*
Y940761D03*
X282958Y1109951D03*
Y1115751D03*
X283808Y1284622D03*
Y1290422D03*
X270234Y1458162D03*
Y1463962D03*
X284086Y1634843D03*
Y1640643D03*
X281066Y1809071D03*
Y1814871D03*
X294483Y57918D03*
Y63718D03*
X314562Y1983607D03*
Y1989407D03*
G54D17*
X17480Y599901D03*
Y627264D03*
Y1471949D03*
Y1499311D03*
G54D27*
X56337Y878761D03*
X388591Y62106D03*
X385616Y1991570D03*
G54D36*
X307086Y308267D03*
G54D18*
X9606Y599901D03*
Y627264D03*
Y1471949D03*
Y1499311D03*
G54D37*
X307086Y1883071D03*
G54D28*
X54413Y1253378D03*
X51263D03*
X54210Y1263103D03*
X51060D03*
X54277Y1257633D03*
X51127D03*
X54582Y1279783D03*
X51432D03*
X54548Y1267290D03*
X51398D03*
X54446Y1284038D03*
X51296D03*
X54582Y1275630D03*
X51432D03*
X54481Y1271544D03*
X51331D03*
X61280Y1559138D03*
X58130D03*
X105845Y20080D03*
X108995D03*
X100778Y28320D03*
X103928D03*
X100693Y24203D03*
X103843D03*
X105845Y15847D03*
X108995D03*
X108090Y46285D03*
X104940D03*
X104932Y41803D03*
X108082D03*
X100778Y32853D03*
X103928D03*
X100778Y37438D03*
X103928D03*
X104137Y78186D03*
X107287D03*
X102727Y58250D03*
X105877D03*
X100518Y391220D03*
X103668D03*
X100518Y376580D03*
X103668D03*
X100518Y386235D03*
X103668D03*
X100518Y381386D03*
X103668D03*
X100518Y371909D03*
X103668D03*
X100518Y396024D03*
X103668D03*
X100794Y400352D03*
X103944D03*
X104518Y426104D03*
X107668D03*
X101056Y720745D03*
X104206D03*
X101056Y730398D03*
X104206D03*
X101056Y725457D03*
X104206D03*
X101056Y715937D03*
X104206D03*
X104346Y745139D03*
X101196D03*
X101056Y735248D03*
X104206D03*
X101056Y739962D03*
X104206D03*
X101520Y749481D03*
X104670D03*
X104442Y774100D03*
X107592D03*
X101189Y1067515D03*
X104339D03*
X101189Y1092036D03*
X104339D03*
X101189Y1072226D03*
X104339D03*
X101189Y1081791D03*
X104339D03*
X101189Y1076901D03*
X104339D03*
X101189Y1087095D03*
X104339D03*
X104432Y1096403D03*
X101282D03*
X105880Y1102535D03*
X109030D03*
X105684Y1122166D03*
X108834D03*
X100227Y1419492D03*
X103377D03*
X100227Y1429195D03*
X103377D03*
X100227Y1424340D03*
X103377D03*
X103443Y1447919D03*
X100293D03*
X100227Y1443743D03*
X103377D03*
X100227Y1434041D03*
X103377D03*
X100227Y1438980D03*
X103377D03*
X100019Y1453131D03*
X103169D03*
X105390Y1470205D03*
X108540D03*
X101677Y1760827D03*
X104827D03*
X101677Y1770527D03*
X104827D03*
X101677Y1765722D03*
X104827D03*
X104930Y1789947D03*
X101780D03*
X101677Y1785571D03*
X104827D03*
X101677Y1775514D03*
X104827D03*
X101677Y1780542D03*
X104827D03*
X105669Y1818228D03*
X108819D03*
X103671Y1798224D03*
X106821D03*
X159676Y56744D03*
X156526D03*
X158463Y68130D03*
X155313D03*
X155202Y72497D03*
X158352D03*
X158559Y88108D03*
X155409D03*
X158490Y407575D03*
X155340D03*
X158498Y436119D03*
X155348D03*
X158950Y756757D03*
X155800D03*
X158665Y764231D03*
X155515D03*
X155113Y776673D03*
X158263D03*
X158519Y784141D03*
X155369D03*
X159278Y1106853D03*
X156128D03*
X158497Y1132178D03*
X155347D03*
X160252Y1457084D03*
X157102D03*
X158976Y1480269D03*
X155826D03*
X159505Y1462651D03*
X156355D03*
X155648Y1473020D03*
X158798D03*
X158840Y1807740D03*
X155690D03*
X158563Y1815631D03*
X155413D03*
X158806Y1828225D03*
X155656D03*
X155409Y1820360D03*
X158559D03*
X184373Y937979D03*
X181223D03*
X184284Y943579D03*
X181134D03*
X184196Y962671D03*
X181046D03*
X184285Y957071D03*
X181135D03*
X184539Y973554D03*
X181389D03*
X184397Y990958D03*
X181247D03*
X184632Y979154D03*
X181482D03*
X184353Y996558D03*
X181203D03*
X184118Y1015313D03*
X180968D03*
X184115Y1009713D03*
X180965D03*
X182329Y1025022D03*
X179179D03*
X182327Y1030622D03*
X179177D03*
X264685Y128228D03*
X261535D03*
X264929Y115559D03*
X261779D03*
X264175Y823604D03*
X261025D03*
X264335Y812170D03*
X261185D03*
X272111Y463099D03*
X268961D03*
X272038Y473677D03*
X268888D03*
X288712Y1864565D03*
X285562D03*
X288794Y1858668D03*
X285644D03*
X308906Y1524401D03*
X305756D03*
X308636Y1513883D03*
X305486D03*
X320208Y1162266D03*
X317058D03*
X320264Y1172804D03*
X317114D03*
G54D19*
X15547Y707364D03*
X25389D03*
X7673Y703427D03*
X15547Y715238D03*
Y723112D03*
Y730986D03*
X25389Y715238D03*
Y723112D03*
Y730986D03*
X7673Y711301D03*
Y719175D03*
Y727049D03*
X15547Y738860D03*
Y746734D03*
Y754608D03*
X25389Y738860D03*
Y746734D03*
Y754608D03*
X7673Y734923D03*
Y742797D03*
Y750671D03*
Y758545D03*
X15547Y762483D03*
Y770357D03*
Y778231D03*
X25389Y762483D03*
Y770357D03*
Y778231D03*
X7673Y766419D03*
Y774293D03*
Y782167D03*
X15547Y786105D03*
Y793979D03*
Y801853D03*
X25389Y786105D03*
Y793979D03*
Y801853D03*
X7673Y790041D03*
Y797915D03*
Y805790D03*
X15547Y809727D03*
Y817601D03*
Y825475D03*
X25389Y809727D03*
Y817601D03*
Y825475D03*
X7673Y813664D03*
Y821538D03*
Y829412D03*
X15547Y833349D03*
Y841223D03*
Y849097D03*
X25389Y833349D03*
Y841223D03*
Y849097D03*
X7673Y837286D03*
Y845160D03*
Y853034D03*
X15547Y856971D03*
Y864845D03*
Y872719D03*
X25389Y856971D03*
Y864845D03*
Y872719D03*
X7673Y860908D03*
Y868782D03*
Y876656D03*
X15547Y880593D03*
Y888467D03*
Y896341D03*
X25389Y880593D03*
Y888467D03*
Y896341D03*
X7673Y884530D03*
Y892404D03*
Y900278D03*
X15547Y904215D03*
Y912089D03*
Y919963D03*
X25389Y904215D03*
Y912089D03*
Y919963D03*
X7673Y908152D03*
Y916026D03*
Y923900D03*
X15547Y927837D03*
Y935711D03*
Y943585D03*
Y951459D03*
X25389Y927837D03*
Y935711D03*
Y943585D03*
Y951459D03*
X7673Y931774D03*
Y939648D03*
Y947522D03*
X15547Y959333D03*
Y967207D03*
Y975081D03*
X25389Y959333D03*
Y967207D03*
Y975081D03*
X7673Y955396D03*
Y963270D03*
Y971144D03*
Y979018D03*
Y994766D03*
X15547Y990829D03*
Y998703D03*
X25389Y990829D03*
Y998703D03*
X7673Y1002640D03*
Y1010514D03*
Y1018388D03*
X15547Y1006577D03*
Y1014451D03*
Y1022325D03*
X25389Y1006577D03*
Y1014451D03*
Y1022325D03*
X7673Y1026262D03*
X15547Y1030199D03*
X15551Y1065629D03*
X25393D03*
X7677Y1061692D03*
Y1069566D03*
X15551Y1073503D03*
Y1081377D03*
Y1089251D03*
X25393Y1073503D03*
Y1081377D03*
Y1089251D03*
X7677Y1077440D03*
Y1085314D03*
Y1093188D03*
X15551Y1097125D03*
Y1104999D03*
Y1112873D03*
Y1120748D03*
X25393Y1097125D03*
Y1104999D03*
Y1112873D03*
Y1120748D03*
X7677Y1101062D03*
Y1108936D03*
Y1116810D03*
X15551Y1128622D03*
Y1136496D03*
Y1144370D03*
X25393Y1128622D03*
Y1136496D03*
Y1144370D03*
X7677Y1124684D03*
Y1132558D03*
Y1140432D03*
X15551Y1152244D03*
Y1160118D03*
Y1167992D03*
X25393Y1152244D03*
Y1160118D03*
Y1167992D03*
X7677Y1148306D03*
Y1156180D03*
Y1164055D03*
X15551Y1175866D03*
Y1183740D03*
Y1191614D03*
X25393Y1175866D03*
Y1183740D03*
Y1191614D03*
X7677Y1171929D03*
Y1179803D03*
Y1187677D03*
X15551Y1199488D03*
Y1207362D03*
Y1215236D03*
X25393Y1199488D03*
Y1207362D03*
Y1215236D03*
X7677Y1195551D03*
Y1203425D03*
Y1211299D03*
X15551Y1223110D03*
Y1230984D03*
Y1238858D03*
X25393Y1223110D03*
Y1230984D03*
Y1238858D03*
X7677Y1219173D03*
Y1227047D03*
Y1234921D03*
X15551Y1246732D03*
Y1254606D03*
Y1262480D03*
X25393Y1246732D03*
Y1254606D03*
Y1262480D03*
X7677Y1242795D03*
Y1250669D03*
Y1258543D03*
X15551Y1270354D03*
Y1278228D03*
Y1286102D03*
X25393Y1270354D03*
Y1278228D03*
Y1286102D03*
X7677Y1266417D03*
Y1274291D03*
Y1282165D03*
X15551Y1293976D03*
Y1301850D03*
Y1309724D03*
X25393Y1293976D03*
Y1301850D03*
Y1309724D03*
X7677Y1290039D03*
Y1297913D03*
Y1305787D03*
Y1313661D03*
X15551Y1317598D03*
Y1325472D03*
Y1333346D03*
X25393Y1317598D03*
Y1325472D03*
Y1333346D03*
X7677Y1321535D03*
Y1329409D03*
Y1337283D03*
Y1353031D03*
Y1360905D03*
X15551Y1349094D03*
Y1356968D03*
X25393Y1349094D03*
Y1356968D03*
X7677Y1368779D03*
Y1376653D03*
Y1384527D03*
X15551Y1364842D03*
Y1372716D03*
Y1380590D03*
X25393Y1364842D03*
Y1372716D03*
Y1380590D03*
X15551Y1388464D03*
X33263Y703427D03*
Y711301D03*
Y719175D03*
Y727049D03*
Y734923D03*
Y742797D03*
Y750671D03*
Y758545D03*
Y766419D03*
Y774293D03*
Y782167D03*
Y790041D03*
Y797915D03*
Y805790D03*
Y813664D03*
Y821538D03*
Y829412D03*
Y837286D03*
Y845160D03*
Y853034D03*
Y860908D03*
Y868782D03*
Y876656D03*
Y884530D03*
Y892404D03*
Y900278D03*
Y908152D03*
Y916026D03*
Y923900D03*
Y931774D03*
Y939648D03*
Y947522D03*
Y955396D03*
Y963270D03*
Y971144D03*
Y979018D03*
Y994766D03*
Y1002640D03*
Y1010514D03*
Y1018388D03*
Y1026262D03*
X33267Y1061692D03*
Y1069566D03*
Y1077440D03*
Y1085314D03*
Y1093188D03*
Y1101062D03*
Y1108936D03*
Y1116810D03*
Y1124684D03*
Y1132558D03*
Y1140432D03*
Y1148306D03*
Y1156180D03*
Y1164055D03*
Y1171929D03*
Y1179803D03*
Y1187677D03*
Y1195551D03*
Y1203425D03*
Y1211299D03*
Y1219173D03*
Y1227047D03*
Y1234921D03*
Y1242795D03*
Y1250669D03*
Y1258543D03*
Y1266417D03*
Y1274291D03*
Y1282165D03*
Y1290039D03*
Y1297913D03*
Y1305787D03*
Y1313661D03*
Y1321535D03*
Y1329409D03*
Y1337283D03*
Y1353031D03*
Y1360905D03*
Y1368779D03*
Y1376653D03*
Y1384527D03*
G54D38*
X359842Y78780D03*
Y253780D03*
Y428779D03*
Y603779D03*
Y778780D03*
Y953780D03*
Y1128779D03*
Y1303780D03*
Y1478780D03*
Y1653780D03*
Y1828779D03*
Y2003780D03*
G54D29*
X71866Y1315303D03*
X66866D03*
X61866D03*
X56866D03*
Y1336103D03*
X61866D03*
X66866D03*
X71866D03*
G54D39*
G01X104331Y0D02*
X397638D01*
G03X405512Y7874I0J7874D01*
G01Y2078740D01*
G03X397638Y2086614I-7874J0D01*
G01X104331D01*
G03X98425Y2080709I0J-5906D01*
G01Y2076772D01*
G02X92520Y2070866I-5905J-1D01*
G01X5906D01*
G03X0Y2064961I-1J-5905D01*
G01Y21654D01*
G03X5906Y15748I5906J0D01*
G01X92520D01*
G02X98425Y9843I0J-5905D01*
G01Y5906D01*
G03X104331Y0I5906J0D01*
M02*
